FILE_TYPE = MACRO_DRAWING;
SET COLOR_WIRE YELLOW;
SET COLOR_PROP ORANGE;
SET COLOR_DOT WHITE;
SET COLOR_ARC YELLOW;
SET COLOR_BODY GREEN;
SET COLOR_NOTE PURPLE;
SET PROP_DISPLAY VALUE;
SET PAGE_NUMBER P33;
FORCEADD MEC_MTH8..1
(-3400 6550);
FORCEPROP 0 LASTPIN (-3500 5800) $PN 8
J 2
(-3510 5810);
DISPLAY 0.680851 (-3510 5810);
PAINT MONO (-3510 5810);
FORCEPROP 0 LASTPIN (-3500 5900) $PN 7
J 2
(-3510 5910);
DISPLAY 0.680851 (-3510 5910);
PAINT MONO (-3510 5910);
FORCEPROP 0 LASTPIN (-3500 6000) $PN 6
J 2
(-3510 6010);
DISPLAY 0.680851 (-3510 6010);
PAINT MONO (-3510 6010);
FORCEPROP 0 LASTPIN (-3500 6100) $PN 5
J 2
(-3510 6110);
DISPLAY 0.680851 (-3510 6110);
PAINT MONO (-3510 6110);
FORCEPROP 0 LASTPIN (-3500 6200) $PN 4
J 2
(-3510 6210);
DISPLAY 0.680851 (-3510 6210);
PAINT MONO (-3510 6210);
FORCEPROP 0 LASTPIN (-3500 6300) $PN 3
J 2
(-3510 6310);
DISPLAY 0.680851 (-3510 6310);
PAINT MONO (-3510 6310);
FORCEPROP 0 LASTPIN (-3500 6500) $PN 1
J 2
(-3510 6510);
DISPLAY 0.680851 (-3510 6510);
PAINT MONO (-3510 6510);
FORCEPROP 0 LASTPIN (-3500 6400) $PN 2
J 2
(-3510 6410);
DISPLAY 0.680851 (-3510 6410);
PAINT MONO (-3510 6410);
FORCEPROP 1 LAST $LOCATION ME11
J 0
(-3400 6600);
DISPLAY 0.808511 (-3400 6600);
PAINT GREEN (-3400 6600);
FORCEPROP 0 LAST CDS_SEC 1
J 0
(-3400 6650);
DISPLAY 1.021277 (-3400 6650);
DISPLAY INVISIBLE (-3400 6650);
FORCEPROP 0 LAST $SEC 1
J 0
(-3400 6650);
DISPLAY 0.680851 (-3400 6650);
PAINT MONO (-3400 6650);
DISPLAY INVISIBLE (-3400 6650);
FORCEPROP 0 LAST CDS_LOCATION ME11
J 0
(-3400 6650);
DISPLAY 1.021277 (-3400 6650);
DISPLAY INVISIBLE (-3400 6650);
FORCEPROP 1 LAST CDS_LMAN_SYM_OUTLINE 0,0,100,-800
J 0
(-3400 6550);
DISPLAY 0.468085 (-3400 6550);
PAINT GREEN (-3400 6550);
DISPLAY INVISIBLE (-3400 6550);
FORCEPROP 1 LAST BOM_IGNORE TRUE
J 0
(-3474 6600);
DISPLAY 0.000000 (-3474 6600);
PAINT GREEN (-3474 6600);
DISPLAY INVISIBLE (-3474 6600);
FORCEPROP 2 LAST CDS_LIB mech
J 0
(-3400 6550);
DISPLAY INVISIBLE (-3400 6550);
FORCEPROP 1 LAST JEDEC_TYPE MTH125C236N_V8
J 0
(-3474 6600);
DISPLAY 0.000000 (-3474 6600);
PAINT GREEN (-3474 6600);
DISPLAY INVISIBLE (-3474 6600);
FORCEPROP 1 LAST PATH I1
J 0
(-3270 6613);
DISPLAY 0.808511 (-3270 6613);
PAINT GREEN (-3270 6613);
DISPLAY INVISIBLE (-3270 6613);
FORCEADD MEC_NPTH..1
(-5250 7550);
FORCEPROP 1 LAST $LOCATION ME8
J 0
(-5300 7700);
DISPLAY 1.212766 (-5300 7700);
PAINT GREEN (-5300 7700);
FORCEPROP 0 LAST CDS_LOCATION ME8
J 0
(-5300 7800);
DISPLAY 1.021277 (-5300 7800);
DISPLAY INVISIBLE (-5300 7800);
FORCEPROP 1 LAST PATH I120
J 0
(-5300 7650);
DISPLAY 1.212766 (-5300 7650);
PAINT GREEN (-5300 7650);
DISPLAY INVISIBLE (-5300 7650);
FORCEPROP 1 LAST JEDEC_TYPE MTH100C240N
J 0
(-5324 7600);
DISPLAY 0.000000 (-5324 7600);
PAINT GREEN (-5324 7600);
DISPLAY INVISIBLE (-5324 7600);
FORCEPROP 1 LAST BOM_IGNORE TRUE
J 0
(-5324 7600);
DISPLAY 0.000000 (-5324 7600);
PAINT GREEN (-5324 7600);
DISPLAY INVISIBLE (-5324 7600);
FORCEPROP 1 LAST CDS_LMAN_SYM_OUTLINE -100,100,100,-100
J 0
(-5250 7550);
DISPLAY 0.468085 (-5250 7550);
PAINT GREEN (-5250 7550);
DISPLAY INVISIBLE (-5250 7550);
FORCEPROP 2 LAST CDS_LIB mech
J 0
(-5250 7550);
DISPLAY INVISIBLE (-5250 7550);
FORCEADD MEC_NPTH..1
(-5750 7550);
FORCEPROP 1 LAST $LOCATION ME7
J 0
(-5800 7700);
DISPLAY 1.212766 (-5800 7700);
PAINT GREEN (-5800 7700);
FORCEPROP 0 LAST CDS_LOCATION ME7
J 0
(-5800 7800);
DISPLAY 1.021277 (-5800 7800);
DISPLAY INVISIBLE (-5800 7800);
FORCEPROP 1 LAST PATH I121
J 0
(-5800 7650);
DISPLAY 1.212766 (-5800 7650);
PAINT GREEN (-5800 7650);
DISPLAY INVISIBLE (-5800 7650);
FORCEPROP 1 LAST JEDEC_TYPE MTH100C240N
J 0
(-5824 7600);
DISPLAY 0.000000 (-5824 7600);
PAINT GREEN (-5824 7600);
DISPLAY INVISIBLE (-5824 7600);
FORCEPROP 1 LAST BOM_IGNORE TRUE
J 0
(-5824 7600);
DISPLAY 0.000000 (-5824 7600);
PAINT GREEN (-5824 7600);
DISPLAY INVISIBLE (-5824 7600);
FORCEPROP 1 LAST CDS_LMAN_SYM_OUTLINE -100,100,100,-100
J 0
(-5750 7550);
DISPLAY 0.468085 (-5750 7550);
PAINT GREEN (-5750 7550);
DISPLAY INVISIBLE (-5750 7550);
FORCEPROP 2 LAST CDS_LIB mech
J 0
(-5750 7550);
DISPLAY INVISIBLE (-5750 7550);
FORCEADD MEC_NPTH..1
(-6250 7550);
FORCEPROP 1 LAST $LOCATION ME6
J 0
(-6300 7700);
DISPLAY 1.212766 (-6300 7700);
PAINT GREEN (-6300 7700);
FORCEPROP 0 LAST CDS_LOCATION ME6
J 0
(-6300 7800);
DISPLAY 1.021277 (-6300 7800);
DISPLAY INVISIBLE (-6300 7800);
FORCEPROP 1 LAST PATH I122
J 0
(-6300 7650);
DISPLAY 1.212766 (-6300 7650);
PAINT GREEN (-6300 7650);
DISPLAY INVISIBLE (-6300 7650);
FORCEPROP 1 LAST JEDEC_TYPE MTH100C240N
J 0
(-6324 7600);
DISPLAY 0.000000 (-6324 7600);
PAINT GREEN (-6324 7600);
DISPLAY INVISIBLE (-6324 7600);
FORCEPROP 1 LAST BOM_IGNORE TRUE
J 0
(-6324 7600);
DISPLAY 0.000000 (-6324 7600);
PAINT GREEN (-6324 7600);
DISPLAY INVISIBLE (-6324 7600);
FORCEPROP 1 LAST CDS_LMAN_SYM_OUTLINE -100,100,100,-100
J 0
(-6250 7550);
DISPLAY 0.468085 (-6250 7550);
PAINT GREEN (-6250 7550);
DISPLAY INVISIBLE (-6250 7550);
FORCEPROP 2 LAST CDS_LIB mech
J 0
(-6250 7550);
DISPLAY INVISIBLE (-6250 7550);
FORCEADD MEC_NPTH..1
(-6750 7550);
FORCEPROP 1 LAST $LOCATION ME5
J 0
(-6800 7700);
DISPLAY 1.212766 (-6800 7700);
PAINT GREEN (-6800 7700);
FORCEPROP 0 LAST CDS_LOCATION ME5
J 0
(-6800 7800);
DISPLAY 1.021277 (-6800 7800);
DISPLAY INVISIBLE (-6800 7800);
FORCEPROP 1 LAST JEDEC_TYPE MTH100C240N
J 0
(-6824 7600);
DISPLAY 0.000000 (-6824 7600);
PAINT GREEN (-6824 7600);
DISPLAY INVISIBLE (-6824 7600);
FORCEPROP 2 LAST CDS_LIB mech
J 0
(-6750 7550);
DISPLAY INVISIBLE (-6750 7550);
FORCEPROP 1 LAST BOM_IGNORE TRUE
J 0
(-6824 7600);
DISPLAY 0.000000 (-6824 7600);
PAINT GREEN (-6824 7600);
DISPLAY INVISIBLE (-6824 7600);
FORCEPROP 1 LAST CDS_LMAN_SYM_OUTLINE -100,100,100,-100
J 0
(-6750 7550);
DISPLAY 0.468085 (-6750 7550);
PAINT GREEN (-6750 7550);
DISPLAY INVISIBLE (-6750 7550);
FORCEPROP 1 LAST PATH I123
J 0
(-6800 7650);
DISPLAY 1.212766 (-6800 7650);
PAINT GREEN (-6800 7650);
DISPLAY INVISIBLE (-6800 7650);
FORCEADD GND_SG..1
(-8950 5950);
FORCEPROP 3 LASTPIN (-8900 6000) SIG_NAME SG\g
J 0
(-8890 6010);
DISPLAY 0.659574 (-8890 6010);
PAINT MONO (-8890 6010);
DISPLAY INVISIBLE (-8890 6010);
FORCEPROP 1 LAST HDL_POWER SG
J 1
(-8895 5855);
DISPLAY 0.808511 (-8895 5855);
PAINT GREEN (-8895 5855);
FORCEPROP 1 LAST PATH I124
J 0
(-8915 5950);
DISPLAY 0.808511 (-8915 5950);
PAINT GREEN (-8915 5950);
DISPLAY INVISIBLE (-8915 5950);
FORCEPROP 2 LAST CDS_LIB cls
J 0
(-8950 5950);
DISPLAY INVISIBLE (-8950 5950);
FORCEPROP 1 LAST CDS_LMAN_SYM_OUTLINE 0,0,100,-50
J 0
(-8950 5950);
DISPLAY 0.468085 (-8950 5950);
PAINT GREEN (-8950 5950);
DISPLAY INVISIBLE (-8950 5950);
FORCEPROP 0 LAST VOLTAGE 0
J 0
(-8850 5950);
DISPLAY 1.021277 (-8850 5950);
DISPLAY INVISIBLE (-8850 5950);
FORCEPROP 1 LAST BODY_TYPE PLUMBING
J 0
(-8935 5935);
DISPLAY 0.808511 (-8935 5935);
PAINT GREEN (-8935 5935);
DISPLAY INVISIBLE (-8935 5935);
FORCEADD NUT..1
R 2
(-9350 6850);
FORCEPROP 1 LAST CLS_PN G340-10437-01
J 2
(-9250 7070);
DISPLAY 1.212766 (-9250 7070);
PAINT GREEN (-9250 7070);
FORCEPROP 1 LAST LOCATION ME3
J 2
(-9250 6970);
DISPLAY 1.212766 (-9250 6970);
PAINT GREEN (-9250 6970);
FORCEPROP 0 LAST PART_NUMBER SMTSO-440-12ET
J 0
(-9950 7150);
DISPLAY 1.021277 (-9950 7150);
FORCEPROP 0 LASTPIN (-9200 6850) $PN 1
J 0
(-9190 6860);
DISPLAY 0.680851 (-9190 6860);
PAINT MONO (-9190 6860);
FORCEPROP 0 LAST CDS_SEC 1
J 0
(-9950 7200);
DISPLAY 1.021277 (-9950 7200);
DISPLAY INVISIBLE (-9950 7200);
FORCEPROP 0 LAST $SEC 1
J 0
(-9950 7200);
DISPLAY 0.680851 (-9950 7200);
PAINT MONO (-9950 7200);
DISPLAY INVISIBLE (-9950 7200);
FORCEPROP 1 LAST PATH I125
J 2
(-9250 7020);
DISPLAY 1.212766 (-9250 7020);
PAINT GREEN (-9250 7020);
DISPLAY INVISIBLE (-9250 7020);
FORCEPROP 2 LAST CDS_LIB mech
J 2
(-9350 6850);
DISPLAY INVISIBLE (-9350 6850);
FORCEPROP 1 LAST CDS_LMAN_SYM_OUTLINE -50,50,50,-50
J 2
(-9350 6850);
DISPLAY 0.468085 (-9350 6850);
PAINT GREEN (-9350 6850);
DISPLAY INVISIBLE (-9350 6850);
FORCEADD NUT..1
R 2
(-9350 6150);
FORCEPROP 1 LAST CLS_PN G340-10437-01
J 2
(-9250 6370);
DISPLAY 1.212766 (-9250 6370);
PAINT GREEN (-9250 6370);
FORCEPROP 0 LAST PART_NUMBER SMTSO-440-12ET
J 0
(-9950 6450);
DISPLAY 1.021277 (-9950 6450);
FORCEPROP 1 LAST LOCATION ME4
J 2
(-9250 6270);
DISPLAY 1.212766 (-9250 6270);
PAINT GREEN (-9250 6270);
FORCEPROP 0 LASTPIN (-9200 6150) $PN 1
J 0
(-9190 6160);
DISPLAY 0.680851 (-9190 6160);
PAINT MONO (-9190 6160);
FORCEPROP 0 LAST CDS_SEC 1
J 0
(-9950 6500);
DISPLAY 1.021277 (-9950 6500);
DISPLAY INVISIBLE (-9950 6500);
FORCEPROP 0 LAST $SEC 1
J 0
(-9950 6500);
DISPLAY 0.680851 (-9950 6500);
PAINT MONO (-9950 6500);
DISPLAY INVISIBLE (-9950 6500);
FORCEPROP 1 LAST PATH I126
J 2
(-9250 6320);
DISPLAY 1.212766 (-9250 6320);
PAINT GREEN (-9250 6320);
DISPLAY INVISIBLE (-9250 6320);
FORCEPROP 1 LAST CDS_LMAN_SYM_OUTLINE -50,50,50,-50
J 2
(-9350 6150);
DISPLAY 0.468085 (-9350 6150);
PAINT GREEN (-9350 6150);
DISPLAY INVISIBLE (-9350 6150);
FORCEPROP 2 LAST CDS_LIB mech
J 2
(-9350 6150);
DISPLAY INVISIBLE (-9350 6150);
FORCEADD NUT..1
R 2
(-11400 6850);
FORCEPROP 1 LAST CLS_PN G340-10437-01
J 2
(-11300 7070);
DISPLAY 1.212766 (-11300 7070);
PAINT GREEN (-11300 7070);
FORCEPROP 1 LAST LOCATION ME1
J 2
(-11300 6970);
DISPLAY 1.212766 (-11300 6970);
PAINT GREEN (-11300 6970);
FORCEPROP 0 LAST PART_NUMBER SMTSO-440-12ET
J 0
(-12000 7150);
DISPLAY 1.021277 (-12000 7150);
FORCEPROP 0 LASTPIN (-11250 6850) $PN 1
J 0
(-11240 6860);
DISPLAY 0.680851 (-11240 6860);
PAINT MONO (-11240 6860);
FORCEPROP 0 LAST CDS_SEC 1
J 0
(-12000 7200);
DISPLAY 1.021277 (-12000 7200);
DISPLAY INVISIBLE (-12000 7200);
FORCEPROP 0 LAST $SEC 1
J 0
(-12000 7200);
DISPLAY 0.680851 (-12000 7200);
PAINT MONO (-12000 7200);
DISPLAY INVISIBLE (-12000 7200);
FORCEPROP 2 LAST CDS_LIB mech
J 2
(-11400 6850);
DISPLAY INVISIBLE (-11400 6850);
FORCEPROP 1 LAST CDS_LMAN_SYM_OUTLINE -50,50,50,-50
J 2
(-11400 6850);
DISPLAY 0.468085 (-11400 6850);
PAINT GREEN (-11400 6850);
DISPLAY INVISIBLE (-11400 6850);
FORCEPROP 1 LAST PATH I127
J 2
(-11300 7020);
DISPLAY 1.212766 (-11300 7020);
PAINT GREEN (-11300 7020);
DISPLAY INVISIBLE (-11300 7020);
FORCEADD GND_SG..1
(-11000 5950);
FORCEPROP 3 LASTPIN (-10950 6000) SIG_NAME SG\g
J 0
(-10940 6010);
DISPLAY 0.659574 (-10940 6010);
PAINT MONO (-10940 6010);
DISPLAY INVISIBLE (-10940 6010);
FORCEPROP 1 LAST HDL_POWER SG
J 1
(-10945 5855);
DISPLAY 0.808511 (-10945 5855);
PAINT GREEN (-10945 5855);
FORCEPROP 1 LAST BODY_TYPE PLUMBING
J 0
(-10985 5935);
DISPLAY 0.808511 (-10985 5935);
PAINT GREEN (-10985 5935);
DISPLAY INVISIBLE (-10985 5935);
FORCEPROP 2 LAST CDS_LIB cls
J 0
(-11000 5950);
DISPLAY INVISIBLE (-11000 5950);
FORCEPROP 1 LAST CDS_LMAN_SYM_OUTLINE 0,0,100,-50
J 0
(-11000 5950);
DISPLAY 0.468085 (-11000 5950);
PAINT GREEN (-11000 5950);
DISPLAY INVISIBLE (-11000 5950);
FORCEPROP 0 LAST VOLTAGE 0
J 0
(-10900 5950);
DISPLAY 1.021277 (-10900 5950);
DISPLAY INVISIBLE (-10900 5950);
FORCEPROP 1 LAST PATH I128
J 0
(-10965 5950);
DISPLAY 0.808511 (-10965 5950);
PAINT GREEN (-10965 5950);
DISPLAY INVISIBLE (-10965 5950);
FORCEADD NUT..1
R 2
(-11400 6150);
FORCEPROP 1 LAST CLS_PN G340-10437-01
J 2
(-11300 6370);
DISPLAY 1.212766 (-11300 6370);
PAINT GREEN (-11300 6370);
FORCEPROP 1 LAST LOCATION ME2
J 2
(-11300 6270);
DISPLAY 1.212766 (-11300 6270);
PAINT GREEN (-11300 6270);
FORCEPROP 0 LASTPIN (-11250 6150) $PN 1
J 0
(-11240 6160);
DISPLAY 0.680851 (-11240 6160);
PAINT MONO (-11240 6160);
FORCEPROP 0 LAST PART_NUMBER SMTSO-440-12ET
J 0
(-12000 6450);
DISPLAY 1.021277 (-12000 6450);
FORCEPROP 0 LAST CDS_SEC 1
J 0
(-12000 6500);
DISPLAY 1.021277 (-12000 6500);
DISPLAY INVISIBLE (-12000 6500);
FORCEPROP 0 LAST $SEC 1
J 0
(-12000 6500);
DISPLAY 0.680851 (-12000 6500);
PAINT MONO (-12000 6500);
DISPLAY INVISIBLE (-12000 6500);
FORCEPROP 1 LAST CDS_LMAN_SYM_OUTLINE -50,50,50,-50
J 2
(-11400 6150);
DISPLAY 0.468085 (-11400 6150);
PAINT GREEN (-11400 6150);
DISPLAY INVISIBLE (-11400 6150);
FORCEPROP 2 LAST CDS_LIB mech
J 2
(-11400 6150);
DISPLAY INVISIBLE (-11400 6150);
FORCEPROP 1 LAST PATH I129
J 2
(-11300 6320);
DISPLAY 1.212766 (-11300 6320);
PAINT GREEN (-11300 6320);
DISPLAY INVISIBLE (-11300 6320);
FORCEADD SOLDER_PREFORM..1
(-12750 2100);
FORCEPROP 0 LASTPIN (-12850 2000) $PN 1
J 2
(-12860 2010);
DISPLAY 0.680851 (-12860 2010);
PAINT MONO (-12860 2010);
FORCEPROP 0 LASTPIN (-12400 2000) $PN 2
J 0
(-12390 2010);
DISPLAY 0.680851 (-12390 2010);
PAINT MONO (-12390 2010);
FORCEPROP 1 LAST CLS_PN G380-10015-01
J 0
(-12750 2200);
DISPLAY 1.212766 (-12750 2200);
PAINT GREEN (-12750 2200);
FORCEPROP 1 LAST LOCATION SP4
J 0
(-12750 2100);
DISPLAY 1.212766 (-12750 2100);
PAINT GREEN (-12750 2100);
FORCEPROP 1 LAST CDS_LMAN_SYM_OUTLINE 0,0,250,-200
J 0
(-12750 2100);
DISPLAY 0.468085 (-12750 2100);
PAINT GREEN (-12750 2100);
DISPLAY INVISIBLE (-12750 2100);
FORCEPROP 1 LAST PATH I130
J 0
(-12700 2150);
DISPLAY 1.212766 (-12700 2150);
PAINT GREEN (-12700 2150);
DISPLAY INVISIBLE (-12700 2150);
FORCEPROP 2 LAST CDS_LIB mech
J 0
(-12750 2100);
DISPLAY INVISIBLE (-12750 2100);
FORCEPROP 0 LAST $SEC 1
J 0
(-12750 2300);
DISPLAY 0.680851 (-12750 2300);
PAINT MONO (-12750 2300);
DISPLAY INVISIBLE (-12750 2300);
FORCEPROP 0 LAST CDS_SEC 1
J 0
(-12750 2300);
DISPLAY 1.021277 (-12750 2300);
DISPLAY INVISIBLE (-12750 2300);
FORCEADD SOLDER_PREFORM..1
(-11850 2100);
FORCEPROP 0 LASTPIN (-11950 2000) $PN 1
J 2
(-11960 2010);
DISPLAY 0.680851 (-11960 2010);
PAINT MONO (-11960 2010);
FORCEPROP 0 LASTPIN (-11500 2000) $PN 2
J 0
(-11490 2010);
DISPLAY 0.680851 (-11490 2010);
PAINT MONO (-11490 2010);
FORCEPROP 1 LAST CLS_PN G380-10015-01
J 0
(-11850 2200);
DISPLAY 1.212766 (-11850 2200);
PAINT GREEN (-11850 2200);
FORCEPROP 1 LAST LOCATION SP5
J 0
(-11850 2100);
DISPLAY 1.212766 (-11850 2100);
PAINT GREEN (-11850 2100);
FORCEPROP 1 LAST CDS_LMAN_SYM_OUTLINE 0,0,250,-200
J 0
(-11850 2100);
DISPLAY 0.468085 (-11850 2100);
PAINT GREEN (-11850 2100);
DISPLAY INVISIBLE (-11850 2100);
FORCEPROP 2 LAST CDS_LIB mech
J 0
(-11850 2100);
DISPLAY INVISIBLE (-11850 2100);
FORCEPROP 1 LAST PATH I131
J 0
(-11800 2150);
DISPLAY 1.212766 (-11800 2150);
PAINT GREEN (-11800 2150);
DISPLAY INVISIBLE (-11800 2150);
FORCEPROP 0 LAST $SEC 1
J 0
(-11850 2300);
DISPLAY 0.680851 (-11850 2300);
PAINT MONO (-11850 2300);
DISPLAY INVISIBLE (-11850 2300);
FORCEPROP 0 LAST CDS_SEC 1
J 0
(-11850 2300);
DISPLAY 1.021277 (-11850 2300);
DISPLAY INVISIBLE (-11850 2300);
FORCEADD SOLDER_PREFORM..1
(-10100 2100);
FORCEPROP 0 LASTPIN (-10200 2000) $PN 1
J 2
(-10210 2010);
DISPLAY 0.680851 (-10210 2010);
PAINT MONO (-10210 2010);
FORCEPROP 0 LASTPIN (-9750 2000) $PN 2
J 0
(-9740 2010);
DISPLAY 0.680851 (-9740 2010);
PAINT MONO (-9740 2010);
FORCEPROP 1 LAST CLS_PN G380-10015-01
J 0
(-10100 2200);
DISPLAY 1.212766 (-10100 2200);
PAINT GREEN (-10100 2200);
FORCEPROP 1 LAST LOCATION SP7
J 0
(-10100 2100);
DISPLAY 1.212766 (-10100 2100);
PAINT GREEN (-10100 2100);
FORCEPROP 2 LAST CDS_LIB mech
J 0
(-10100 2100);
DISPLAY INVISIBLE (-10100 2100);
FORCEPROP 1 LAST CDS_LMAN_SYM_OUTLINE 0,0,250,-200
J 0
(-10100 2100);
DISPLAY 0.468085 (-10100 2100);
PAINT GREEN (-10100 2100);
DISPLAY INVISIBLE (-10100 2100);
FORCEPROP 1 LAST PATH I132
J 0
(-10050 2150);
DISPLAY 1.212766 (-10050 2150);
PAINT GREEN (-10050 2150);
DISPLAY INVISIBLE (-10050 2150);
FORCEPROP 0 LAST $SEC 1
J 0
(-10100 2300);
DISPLAY 0.680851 (-10100 2300);
PAINT MONO (-10100 2300);
DISPLAY INVISIBLE (-10100 2300);
FORCEPROP 0 LAST CDS_SEC 1
J 0
(-10100 2300);
DISPLAY 1.021277 (-10100 2300);
DISPLAY INVISIBLE (-10100 2300);
FORCEADD SOLDER_PREFORM..1
(-11000 2100);
FORCEPROP 1 LAST LOCATION SP6
J 0
(-11000 2100);
DISPLAY 1.212766 (-11000 2100);
PAINT GREEN (-11000 2100);
FORCEPROP 0 LASTPIN (-11100 2000) $PN 1
J 2
(-11110 2010);
DISPLAY 0.680851 (-11110 2010);
PAINT MONO (-11110 2010);
FORCEPROP 0 LASTPIN (-10650 2000) $PN 2
J 0
(-10640 2010);
DISPLAY 0.680851 (-10640 2010);
PAINT MONO (-10640 2010);
FORCEPROP 1 LAST CLS_PN G380-10015-01
J 0
(-11000 2200);
DISPLAY 1.212766 (-11000 2200);
PAINT GREEN (-11000 2200);
FORCEPROP 2 LAST CDS_LIB mech
J 0
(-11000 2100);
DISPLAY INVISIBLE (-11000 2100);
FORCEPROP 1 LAST CDS_LMAN_SYM_OUTLINE 0,0,250,-200
J 0
(-11000 2100);
DISPLAY 0.468085 (-11000 2100);
PAINT GREEN (-11000 2100);
DISPLAY INVISIBLE (-11000 2100);
FORCEPROP 1 LAST PATH I133
J 0
(-10950 2150);
DISPLAY 1.212766 (-10950 2150);
PAINT GREEN (-10950 2150);
DISPLAY INVISIBLE (-10950 2150);
FORCEPROP 0 LAST $SEC 1
J 0
(-11000 2300);
DISPLAY 0.680851 (-11000 2300);
PAINT MONO (-11000 2300);
DISPLAY INVISIBLE (-11000 2300);
FORCEPROP 0 LAST CDS_SEC 1
J 0
(-11000 2300);
DISPLAY 1.021277 (-11000 2300);
DISPLAY INVISIBLE (-11000 2300);
FORCEADD SOLDER_PREFORM..1
(-9150 2100);
FORCEPROP 1 LAST LOCATION SP8
J 0
(-9150 2100);
DISPLAY 1.212766 (-9150 2100);
PAINT GREEN (-9150 2100);
FORCEPROP 0 LASTPIN (-9250 2000) $PN 1
J 2
(-9260 2010);
DISPLAY 0.680851 (-9260 2010);
PAINT MONO (-9260 2010);
FORCEPROP 0 LASTPIN (-8800 2000) $PN 2
J 0
(-8790 2010);
DISPLAY 0.680851 (-8790 2010);
PAINT MONO (-8790 2010);
FORCEPROP 1 LAST CLS_PN G380-10015-01
J 0
(-9150 2200);
DISPLAY 1.212766 (-9150 2200);
PAINT GREEN (-9150 2200);
FORCEPROP 1 LAST PATH I134
J 0
(-9100 2150);
DISPLAY 1.212766 (-9100 2150);
PAINT GREEN (-9100 2150);
DISPLAY INVISIBLE (-9100 2150);
FORCEPROP 1 LAST CDS_LMAN_SYM_OUTLINE 0,0,250,-200
J 0
(-9150 2100);
DISPLAY 0.468085 (-9150 2100);
PAINT GREEN (-9150 2100);
DISPLAY INVISIBLE (-9150 2100);
FORCEPROP 2 LAST CDS_LIB mech
J 0
(-9150 2100);
DISPLAY INVISIBLE (-9150 2100);
FORCEPROP 0 LAST $SEC 1
J 0
(-9150 2300);
DISPLAY 0.680851 (-9150 2300);
PAINT MONO (-9150 2300);
DISPLAY INVISIBLE (-9150 2300);
FORCEPROP 0 LAST CDS_SEC 1
J 0
(-9150 2300);
DISPLAY 1.021277 (-9150 2300);
DISPLAY INVISIBLE (-9150 2300);
FORCEADD SOLDER_PREFORM..1
(-8250 2100);
FORCEPROP 1 LAST LOCATION SP9
J 0
(-8250 2100);
DISPLAY 1.212766 (-8250 2100);
PAINT GREEN (-8250 2100);
FORCEPROP 1 LAST CLS_PN G380-10015-01
J 0
(-8250 2200);
DISPLAY 1.212766 (-8250 2200);
PAINT GREEN (-8250 2200);
FORCEPROP 0 LASTPIN (-7900 2000) $PN 2
J 0
(-7890 2010);
DISPLAY 0.680851 (-7890 2010);
PAINT MONO (-7890 2010);
FORCEPROP 0 LASTPIN (-8350 2000) $PN 1
J 2
(-8360 2010);
DISPLAY 0.680851 (-8360 2010);
PAINT MONO (-8360 2010);
FORCEPROP 1 LAST PATH I135
J 0
(-8200 2150);
DISPLAY 1.212766 (-8200 2150);
PAINT GREEN (-8200 2150);
DISPLAY INVISIBLE (-8200 2150);
FORCEPROP 1 LAST CDS_LMAN_SYM_OUTLINE 0,0,250,-200
J 0
(-8250 2100);
DISPLAY 0.468085 (-8250 2100);
PAINT GREEN (-8250 2100);
DISPLAY INVISIBLE (-8250 2100);
FORCEPROP 2 LAST CDS_LIB mech
J 0
(-8250 2100);
DISPLAY INVISIBLE (-8250 2100);
FORCEPROP 0 LAST $SEC 1
J 0
(-8250 2300);
DISPLAY 0.680851 (-8250 2300);
PAINT MONO (-8250 2300);
DISPLAY INVISIBLE (-8250 2300);
FORCEPROP 0 LAST CDS_SEC 1
J 0
(-8250 2300);
DISPLAY 1.021277 (-8250 2300);
DISPLAY INVISIBLE (-8250 2300);
FORCEADD SOLDER_PREFORM..1
(-6500 2100);
FORCEPROP 1 LAST LOCATION SP11
J 0
(-6500 2100);
DISPLAY 1.212766 (-6500 2100);
PAINT GREEN (-6500 2100);
FORCEPROP 0 LASTPIN (-6600 2000) $PN 1
J 2
(-6610 2010);
DISPLAY 0.680851 (-6610 2010);
PAINT MONO (-6610 2010);
FORCEPROP 0 LASTPIN (-6150 2000) $PN 2
J 0
(-6140 2010);
DISPLAY 0.680851 (-6140 2010);
PAINT MONO (-6140 2010);
FORCEPROP 1 LAST CLS_PN G380-10015-01
J 0
(-6500 2200);
DISPLAY 1.212766 (-6500 2200);
PAINT GREEN (-6500 2200);
FORCEPROP 1 LAST PATH I136
J 0
(-6450 2150);
DISPLAY 1.212766 (-6450 2150);
PAINT GREEN (-6450 2150);
DISPLAY INVISIBLE (-6450 2150);
FORCEPROP 2 LAST CDS_LIB mech
J 0
(-6500 2100);
DISPLAY INVISIBLE (-6500 2100);
FORCEPROP 1 LAST CDS_LMAN_SYM_OUTLINE 0,0,250,-200
J 0
(-6500 2100);
DISPLAY 0.468085 (-6500 2100);
PAINT GREEN (-6500 2100);
DISPLAY INVISIBLE (-6500 2100);
FORCEPROP 0 LAST $SEC 1
J 0
(-6500 2300);
DISPLAY 0.680851 (-6500 2300);
PAINT MONO (-6500 2300);
DISPLAY INVISIBLE (-6500 2300);
FORCEPROP 0 LAST CDS_SEC 1
J 0
(-6500 2300);
DISPLAY 1.021277 (-6500 2300);
DISPLAY INVISIBLE (-6500 2300);
FORCEADD SOLDER_PREFORM..1
(-7400 2100);
FORCEPROP 0 LASTPIN (-7500 2000) $PN 1
J 2
(-7510 2010);
DISPLAY 0.680851 (-7510 2010);
PAINT MONO (-7510 2010);
FORCEPROP 0 LASTPIN (-7050 2000) $PN 2
J 0
(-7040 2010);
DISPLAY 0.680851 (-7040 2010);
PAINT MONO (-7040 2010);
FORCEPROP 1 LAST CLS_PN G380-10015-01
J 0
(-7400 2200);
DISPLAY 1.212766 (-7400 2200);
PAINT GREEN (-7400 2200);
FORCEPROP 1 LAST LOCATION SP10
J 0
(-7400 2100);
DISPLAY 1.212766 (-7400 2100);
PAINT GREEN (-7400 2100);
FORCEPROP 1 LAST PATH I137
J 0
(-7350 2150);
DISPLAY 1.212766 (-7350 2150);
PAINT GREEN (-7350 2150);
DISPLAY INVISIBLE (-7350 2150);
FORCEPROP 2 LAST CDS_LIB mech
J 0
(-7400 2100);
DISPLAY INVISIBLE (-7400 2100);
FORCEPROP 1 LAST CDS_LMAN_SYM_OUTLINE 0,0,250,-200
J 0
(-7400 2100);
DISPLAY 0.468085 (-7400 2100);
PAINT GREEN (-7400 2100);
DISPLAY INVISIBLE (-7400 2100);
FORCEPROP 0 LAST $SEC 1
J 0
(-7400 2300);
DISPLAY 0.680851 (-7400 2300);
PAINT MONO (-7400 2300);
DISPLAY INVISIBLE (-7400 2300);
FORCEPROP 0 LAST CDS_SEC 1
J 0
(-7400 2300);
DISPLAY 1.021277 (-7400 2300);
DISPLAY INVISIBLE (-7400 2300);
FORCEADD SOLDER_PREFORM..1
(-2900 2100);
FORCEPROP 1 LAST LOCATION SP15
J 0
(-2900 2100);
DISPLAY 1.212766 (-2900 2100);
PAINT GREEN (-2900 2100);
FORCEPROP 0 LASTPIN (-2550 2000) $PN 2
J 0
(-2540 2010);
DISPLAY 0.680851 (-2540 2010);
PAINT MONO (-2540 2010);
FORCEPROP 0 LASTPIN (-3000 2000) $PN 1
J 2
(-3010 2010);
DISPLAY 0.680851 (-3010 2010);
PAINT MONO (-3010 2010);
FORCEPROP 1 LAST CLS_PN G380-10015-01
J 0
(-2900 2200);
DISPLAY 1.212766 (-2900 2200);
PAINT GREEN (-2900 2200);
FORCEPROP 1 LAST PATH I138
J 0
(-2850 2150);
DISPLAY 1.212766 (-2850 2150);
PAINT GREEN (-2850 2150);
DISPLAY INVISIBLE (-2850 2150);
FORCEPROP 2 LAST CDS_LIB mech
J 0
(-2900 2100);
DISPLAY INVISIBLE (-2900 2100);
FORCEPROP 1 LAST CDS_LMAN_SYM_OUTLINE 0,0,250,-200
J 0
(-2900 2100);
DISPLAY 0.468085 (-2900 2100);
PAINT GREEN (-2900 2100);
DISPLAY INVISIBLE (-2900 2100);
FORCEPROP 0 LAST $SEC 1
J 0
(-2900 2300);
DISPLAY 0.680851 (-2900 2300);
PAINT MONO (-2900 2300);
DISPLAY INVISIBLE (-2900 2300);
FORCEPROP 0 LAST CDS_SEC 1
J 0
(-2900 2300);
DISPLAY 1.021277 (-2900 2300);
DISPLAY INVISIBLE (-2900 2300);
FORCEADD SOLDER_PREFORM..1
(-3800 2100);
FORCEPROP 0 LASTPIN (-3900 2000) $PN 1
J 2
(-3910 2010);
DISPLAY 0.680851 (-3910 2010);
PAINT MONO (-3910 2010);
FORCEPROP 0 LASTPIN (-3450 2000) $PN 2
J 0
(-3440 2010);
DISPLAY 0.680851 (-3440 2010);
PAINT MONO (-3440 2010);
FORCEPROP 1 LAST CLS_PN G380-10015-01
J 0
(-3800 2200);
DISPLAY 1.212766 (-3800 2200);
PAINT GREEN (-3800 2200);
FORCEPROP 1 LAST LOCATION SP14
J 0
(-3800 2100);
DISPLAY 1.212766 (-3800 2100);
PAINT GREEN (-3800 2100);
FORCEPROP 1 LAST PATH I139
J 0
(-3750 2150);
DISPLAY 1.212766 (-3750 2150);
PAINT GREEN (-3750 2150);
DISPLAY INVISIBLE (-3750 2150);
FORCEPROP 2 LAST CDS_LIB mech
J 0
(-3800 2100);
DISPLAY INVISIBLE (-3800 2100);
FORCEPROP 1 LAST CDS_LMAN_SYM_OUTLINE 0,0,250,-200
J 0
(-3800 2100);
DISPLAY 0.468085 (-3800 2100);
PAINT GREEN (-3800 2100);
DISPLAY INVISIBLE (-3800 2100);
FORCEPROP 0 LAST $SEC 1
J 0
(-3800 2300);
DISPLAY 0.680851 (-3800 2300);
PAINT MONO (-3800 2300);
DISPLAY INVISIBLE (-3800 2300);
FORCEPROP 0 LAST CDS_SEC 1
J 0
(-3800 2300);
DISPLAY 1.021277 (-3800 2300);
DISPLAY INVISIBLE (-3800 2300);
FORCEADD SOLDER_PREFORM..1
(-4650 2100);
FORCEPROP 1 LAST LOCATION SP13
J 0
(-4650 2100);
DISPLAY 1.212766 (-4650 2100);
PAINT GREEN (-4650 2100);
FORCEPROP 0 LASTPIN (-4750 2000) $PN 1
J 2
(-4760 2010);
DISPLAY 0.680851 (-4760 2010);
PAINT MONO (-4760 2010);
FORCEPROP 0 LASTPIN (-4300 2000) $PN 2
J 0
(-4290 2010);
DISPLAY 0.680851 (-4290 2010);
PAINT MONO (-4290 2010);
FORCEPROP 1 LAST CLS_PN G380-10015-01
J 0
(-4650 2200);
DISPLAY 1.212766 (-4650 2200);
PAINT GREEN (-4650 2200);
FORCEPROP 1 LAST PATH I140
J 0
(-4600 2150);
DISPLAY 1.212766 (-4600 2150);
PAINT GREEN (-4600 2150);
DISPLAY INVISIBLE (-4600 2150);
FORCEPROP 1 LAST CDS_LMAN_SYM_OUTLINE 0,0,250,-200
J 0
(-4650 2100);
DISPLAY 0.468085 (-4650 2100);
PAINT GREEN (-4650 2100);
DISPLAY INVISIBLE (-4650 2100);
FORCEPROP 2 LAST CDS_LIB mech
J 0
(-4650 2100);
DISPLAY INVISIBLE (-4650 2100);
FORCEPROP 0 LAST $SEC 1
J 0
(-4650 2300);
DISPLAY 0.680851 (-4650 2300);
PAINT MONO (-4650 2300);
DISPLAY INVISIBLE (-4650 2300);
FORCEPROP 0 LAST CDS_SEC 1
J 0
(-4650 2300);
DISPLAY 1.021277 (-4650 2300);
DISPLAY INVISIBLE (-4650 2300);
FORCEADD SOLDER_PREFORM..1
(-5550 2100);
FORCEPROP 1 LAST LOCATION SP12
J 0
(-5550 2100);
DISPLAY 1.212766 (-5550 2100);
PAINT GREEN (-5550 2100);
FORCEPROP 0 LASTPIN (-5650 2000) $PN 1
J 2
(-5660 2010);
DISPLAY 0.680851 (-5660 2010);
PAINT MONO (-5660 2010);
FORCEPROP 0 LASTPIN (-5200 2000) $PN 2
J 0
(-5190 2010);
DISPLAY 0.680851 (-5190 2010);
PAINT MONO (-5190 2010);
FORCEPROP 1 LAST CLS_PN G380-10015-01
J 0
(-5550 2200);
DISPLAY 1.212766 (-5550 2200);
PAINT GREEN (-5550 2200);
FORCEPROP 1 LAST PATH I141
J 0
(-5500 2150);
DISPLAY 1.212766 (-5500 2150);
PAINT GREEN (-5500 2150);
DISPLAY INVISIBLE (-5500 2150);
FORCEPROP 1 LAST CDS_LMAN_SYM_OUTLINE 0,0,250,-200
J 0
(-5550 2100);
DISPLAY 0.468085 (-5550 2100);
PAINT GREEN (-5550 2100);
DISPLAY INVISIBLE (-5550 2100);
FORCEPROP 2 LAST CDS_LIB mech
J 0
(-5550 2100);
DISPLAY INVISIBLE (-5550 2100);
FORCEPROP 0 LAST $SEC 1
J 0
(-5550 2300);
DISPLAY 0.680851 (-5550 2300);
PAINT MONO (-5550 2300);
DISPLAY INVISIBLE (-5550 2300);
FORCEPROP 0 LAST CDS_SEC 1
J 0
(-5550 2300);
DISPLAY 1.021277 (-5550 2300);
DISPLAY INVISIBLE (-5550 2300);
FORCEADD SOLDER_PREFORM..1
(-11850 1600);
FORCEPROP 1 LAST LOCATION SP17
J 0
(-11850 1600);
DISPLAY 1.212766 (-11850 1600);
PAINT GREEN (-11850 1600);
FORCEPROP 0 LASTPIN (-11950 1500) $PN 1
J 2
(-11960 1510);
DISPLAY 0.680851 (-11960 1510);
PAINT MONO (-11960 1510);
FORCEPROP 0 LASTPIN (-11500 1500) $PN 2
J 0
(-11490 1510);
DISPLAY 0.680851 (-11490 1510);
PAINT MONO (-11490 1510);
FORCEPROP 1 LAST CLS_PN G380-10015-01
J 0
(-11850 1700);
DISPLAY 1.212766 (-11850 1700);
PAINT GREEN (-11850 1700);
FORCEPROP 1 LAST CDS_LMAN_SYM_OUTLINE 0,0,250,-200
J 0
(-11850 1600);
DISPLAY 0.468085 (-11850 1600);
PAINT GREEN (-11850 1600);
DISPLAY INVISIBLE (-11850 1600);
FORCEPROP 2 LAST CDS_LIB mech
J 0
(-11850 1600);
DISPLAY INVISIBLE (-11850 1600);
FORCEPROP 1 LAST PATH I142
J 0
(-11800 1650);
DISPLAY 1.212766 (-11800 1650);
PAINT GREEN (-11800 1650);
DISPLAY INVISIBLE (-11800 1650);
FORCEPROP 0 LAST $SEC 1
J 0
(-11850 1800);
DISPLAY 0.680851 (-11850 1800);
PAINT MONO (-11850 1800);
DISPLAY INVISIBLE (-11850 1800);
FORCEPROP 0 LAST CDS_SEC 1
J 0
(-11850 1800);
DISPLAY 1.021277 (-11850 1800);
DISPLAY INVISIBLE (-11850 1800);
FORCEADD SOLDER_PREFORM..1
(-2900 1600);
FORCEPROP 1 LAST LOCATION SP27
J 0
(-2900 1600);
DISPLAY 1.212766 (-2900 1600);
PAINT GREEN (-2900 1600);
FORCEPROP 0 LASTPIN (-3000 1500) $PN 1
J 2
(-3010 1510);
DISPLAY 0.680851 (-3010 1510);
PAINT MONO (-3010 1510);
FORCEPROP 0 LASTPIN (-2550 1500) $PN 2
J 0
(-2540 1510);
DISPLAY 0.680851 (-2540 1510);
PAINT MONO (-2540 1510);
FORCEPROP 1 LAST CLS_PN G380-10015-01
J 0
(-2900 1700);
DISPLAY 1.212766 (-2900 1700);
PAINT GREEN (-2900 1700);
FORCEPROP 2 LAST CDS_LIB mech
J 0
(-2900 1600);
DISPLAY INVISIBLE (-2900 1600);
FORCEPROP 1 LAST CDS_LMAN_SYM_OUTLINE 0,0,250,-200
J 0
(-2900 1600);
DISPLAY 0.468085 (-2900 1600);
PAINT GREEN (-2900 1600);
DISPLAY INVISIBLE (-2900 1600);
FORCEPROP 1 LAST PATH I143
J 0
(-2850 1650);
DISPLAY 1.212766 (-2850 1650);
PAINT GREEN (-2850 1650);
DISPLAY INVISIBLE (-2850 1650);
FORCEPROP 0 LAST $SEC 1
J 0
(-2900 1800);
DISPLAY 0.680851 (-2900 1800);
PAINT MONO (-2900 1800);
DISPLAY INVISIBLE (-2900 1800);
FORCEPROP 0 LAST CDS_SEC 1
J 0
(-2900 1800);
DISPLAY 1.021277 (-2900 1800);
DISPLAY INVISIBLE (-2900 1800);
FORCEADD SOLDER_PREFORM..1
(-3800 1600);
FORCEPROP 1 LAST LOCATION SP26
J 0
(-3800 1600);
DISPLAY 1.212766 (-3800 1600);
PAINT GREEN (-3800 1600);
FORCEPROP 0 LASTPIN (-3900 1500) $PN 1
J 2
(-3910 1510);
DISPLAY 0.680851 (-3910 1510);
PAINT MONO (-3910 1510);
FORCEPROP 0 LASTPIN (-3450 1500) $PN 2
J 0
(-3440 1510);
DISPLAY 0.680851 (-3440 1510);
PAINT MONO (-3440 1510);
FORCEPROP 1 LAST CLS_PN G380-10015-01
J 0
(-3800 1700);
DISPLAY 1.212766 (-3800 1700);
PAINT GREEN (-3800 1700);
FORCEPROP 2 LAST CDS_LIB mech
J 0
(-3800 1600);
DISPLAY INVISIBLE (-3800 1600);
FORCEPROP 1 LAST CDS_LMAN_SYM_OUTLINE 0,0,250,-200
J 0
(-3800 1600);
DISPLAY 0.468085 (-3800 1600);
PAINT GREEN (-3800 1600);
DISPLAY INVISIBLE (-3800 1600);
FORCEPROP 1 LAST PATH I144
J 0
(-3750 1650);
DISPLAY 1.212766 (-3750 1650);
PAINT GREEN (-3750 1650);
DISPLAY INVISIBLE (-3750 1650);
FORCEPROP 0 LAST $SEC 1
J 0
(-3800 1800);
DISPLAY 0.680851 (-3800 1800);
PAINT MONO (-3800 1800);
DISPLAY INVISIBLE (-3800 1800);
FORCEPROP 0 LAST CDS_SEC 1
J 0
(-3800 1800);
DISPLAY 1.021277 (-3800 1800);
DISPLAY INVISIBLE (-3800 1800);
FORCEADD SOLDER_PREFORM..1
(-4650 1600);
FORCEPROP 0 LASTPIN (-4750 1500) $PN 1
J 2
(-4760 1510);
DISPLAY 0.680851 (-4760 1510);
PAINT MONO (-4760 1510);
FORCEPROP 0 LASTPIN (-4300 1500) $PN 2
J 0
(-4290 1510);
DISPLAY 0.680851 (-4290 1510);
PAINT MONO (-4290 1510);
FORCEPROP 1 LAST CLS_PN G380-10015-01
J 0
(-4650 1700);
DISPLAY 1.212766 (-4650 1700);
PAINT GREEN (-4650 1700);
FORCEPROP 1 LAST LOCATION SP25
J 0
(-4650 1600);
DISPLAY 1.212766 (-4650 1600);
PAINT GREEN (-4650 1600);
FORCEPROP 1 LAST CDS_LMAN_SYM_OUTLINE 0,0,250,-200
J 0
(-4650 1600);
DISPLAY 0.468085 (-4650 1600);
PAINT GREEN (-4650 1600);
DISPLAY INVISIBLE (-4650 1600);
FORCEPROP 2 LAST CDS_LIB mech
J 0
(-4650 1600);
DISPLAY INVISIBLE (-4650 1600);
FORCEPROP 1 LAST PATH I145
J 0
(-4600 1650);
DISPLAY 1.212766 (-4600 1650);
PAINT GREEN (-4600 1650);
DISPLAY INVISIBLE (-4600 1650);
FORCEPROP 0 LAST $SEC 1
J 0
(-4650 1800);
DISPLAY 0.680851 (-4650 1800);
PAINT MONO (-4650 1800);
DISPLAY INVISIBLE (-4650 1800);
FORCEPROP 0 LAST CDS_SEC 1
J 0
(-4650 1800);
DISPLAY 1.021277 (-4650 1800);
DISPLAY INVISIBLE (-4650 1800);
FORCEADD SOLDER_PREFORM..1
(-5550 1600);
FORCEPROP 0 LASTPIN (-5650 1500) $PN 1
J 2
(-5660 1510);
DISPLAY 0.680851 (-5660 1510);
PAINT MONO (-5660 1510);
FORCEPROP 0 LASTPIN (-5200 1500) $PN 2
J 0
(-5190 1510);
DISPLAY 0.680851 (-5190 1510);
PAINT MONO (-5190 1510);
FORCEPROP 1 LAST LOCATION SP24
J 0
(-5550 1600);
DISPLAY 1.212766 (-5550 1600);
PAINT GREEN (-5550 1600);
FORCEPROP 1 LAST CLS_PN G380-10015-01
J 0
(-5550 1700);
DISPLAY 1.212766 (-5550 1700);
PAINT GREEN (-5550 1700);
FORCEPROP 1 LAST CDS_LMAN_SYM_OUTLINE 0,0,250,-200
J 0
(-5550 1600);
DISPLAY 0.468085 (-5550 1600);
PAINT GREEN (-5550 1600);
DISPLAY INVISIBLE (-5550 1600);
FORCEPROP 2 LAST CDS_LIB mech
J 0
(-5550 1600);
DISPLAY INVISIBLE (-5550 1600);
FORCEPROP 1 LAST PATH I146
J 0
(-5500 1650);
DISPLAY 1.212766 (-5500 1650);
PAINT GREEN (-5500 1650);
DISPLAY INVISIBLE (-5500 1650);
FORCEPROP 0 LAST $SEC 1
J 0
(-5550 1800);
DISPLAY 0.680851 (-5550 1800);
PAINT MONO (-5550 1800);
DISPLAY INVISIBLE (-5550 1800);
FORCEPROP 0 LAST CDS_SEC 1
J 0
(-5550 1800);
DISPLAY 1.021277 (-5550 1800);
DISPLAY INVISIBLE (-5550 1800);
FORCEADD SOLDER_PREFORM..1
(-6500 1600);
FORCEPROP 0 LASTPIN (-6600 1500) $PN 1
J 2
(-6610 1510);
DISPLAY 0.680851 (-6610 1510);
PAINT MONO (-6610 1510);
FORCEPROP 0 LASTPIN (-6150 1500) $PN 2
J 0
(-6140 1510);
DISPLAY 0.680851 (-6140 1510);
PAINT MONO (-6140 1510);
FORCEPROP 1 LAST CLS_PN G380-10015-01
J 0
(-6500 1700);
DISPLAY 1.212766 (-6500 1700);
PAINT GREEN (-6500 1700);
FORCEPROP 1 LAST LOCATION SP23
J 0
(-6500 1600);
DISPLAY 1.212766 (-6500 1600);
PAINT GREEN (-6500 1600);
FORCEPROP 2 LAST CDS_LIB mech
J 0
(-6500 1600);
DISPLAY INVISIBLE (-6500 1600);
FORCEPROP 1 LAST CDS_LMAN_SYM_OUTLINE 0,0,250,-200
J 0
(-6500 1600);
DISPLAY 0.468085 (-6500 1600);
PAINT GREEN (-6500 1600);
DISPLAY INVISIBLE (-6500 1600);
FORCEPROP 1 LAST PATH I147
J 0
(-6450 1650);
DISPLAY 1.212766 (-6450 1650);
PAINT GREEN (-6450 1650);
DISPLAY INVISIBLE (-6450 1650);
FORCEPROP 0 LAST $SEC 1
J 0
(-6500 1800);
DISPLAY 0.680851 (-6500 1800);
PAINT MONO (-6500 1800);
DISPLAY INVISIBLE (-6500 1800);
FORCEPROP 0 LAST CDS_SEC 1
J 0
(-6500 1800);
DISPLAY 1.021277 (-6500 1800);
DISPLAY INVISIBLE (-6500 1800);
FORCEADD SOLDER_PREFORM..1
(-7400 1600);
FORCEPROP 1 LAST LOCATION SP22
J 0
(-7400 1600);
DISPLAY 1.212766 (-7400 1600);
PAINT GREEN (-7400 1600);
FORCEPROP 0 LASTPIN (-7500 1500) $PN 1
J 2
(-7510 1510);
DISPLAY 0.680851 (-7510 1510);
PAINT MONO (-7510 1510);
FORCEPROP 0 LASTPIN (-7050 1500) $PN 2
J 0
(-7040 1510);
DISPLAY 0.680851 (-7040 1510);
PAINT MONO (-7040 1510);
FORCEPROP 1 LAST CLS_PN G380-10015-01
J 0
(-7400 1700);
DISPLAY 1.212766 (-7400 1700);
PAINT GREEN (-7400 1700);
FORCEPROP 2 LAST CDS_LIB mech
J 0
(-7400 1600);
DISPLAY INVISIBLE (-7400 1600);
FORCEPROP 1 LAST CDS_LMAN_SYM_OUTLINE 0,0,250,-200
J 0
(-7400 1600);
DISPLAY 0.468085 (-7400 1600);
PAINT GREEN (-7400 1600);
DISPLAY INVISIBLE (-7400 1600);
FORCEPROP 1 LAST PATH I148
J 0
(-7350 1650);
DISPLAY 1.212766 (-7350 1650);
PAINT GREEN (-7350 1650);
DISPLAY INVISIBLE (-7350 1650);
FORCEPROP 0 LAST $SEC 1
J 0
(-7400 1800);
DISPLAY 0.680851 (-7400 1800);
PAINT MONO (-7400 1800);
DISPLAY INVISIBLE (-7400 1800);
FORCEPROP 0 LAST CDS_SEC 1
J 0
(-7400 1800);
DISPLAY 1.021277 (-7400 1800);
DISPLAY INVISIBLE (-7400 1800);
FORCEADD SOLDER_PREFORM..1
(-9150 1600);
FORCEPROP 0 LASTPIN (-8800 1500) $PN 2
J 0
(-8790 1510);
DISPLAY 0.680851 (-8790 1510);
PAINT MONO (-8790 1510);
FORCEPROP 0 LASTPIN (-9250 1500) $PN 1
J 2
(-9260 1510);
DISPLAY 0.680851 (-9260 1510);
PAINT MONO (-9260 1510);
FORCEPROP 1 LAST LOCATION SP20
J 0
(-9150 1600);
DISPLAY 1.212766 (-9150 1600);
PAINT GREEN (-9150 1600);
FORCEPROP 1 LAST CLS_PN G380-10015-01
J 0
(-9150 1700);
DISPLAY 1.212766 (-9150 1700);
PAINT GREEN (-9150 1700);
FORCEPROP 1 LAST CDS_LMAN_SYM_OUTLINE 0,0,250,-200
J 0
(-9150 1600);
DISPLAY 0.468085 (-9150 1600);
PAINT GREEN (-9150 1600);
DISPLAY INVISIBLE (-9150 1600);
FORCEPROP 2 LAST CDS_LIB mech
J 0
(-9150 1600);
DISPLAY INVISIBLE (-9150 1600);
FORCEPROP 1 LAST PATH I149
J 0
(-9100 1650);
DISPLAY 1.212766 (-9100 1650);
PAINT GREEN (-9100 1650);
DISPLAY INVISIBLE (-9100 1650);
FORCEPROP 0 LAST $SEC 1
J 0
(-9150 1800);
DISPLAY 0.680851 (-9150 1800);
PAINT MONO (-9150 1800);
DISPLAY INVISIBLE (-9150 1800);
FORCEPROP 0 LAST CDS_SEC 1
J 0
(-9150 1800);
DISPLAY 1.021277 (-9150 1800);
DISPLAY INVISIBLE (-9150 1800);
FORCEADD SOLDER_PREFORM..1
(-8250 1600);
FORCEPROP 0 LASTPIN (-8350 1500) $PN 1
J 2
(-8360 1510);
DISPLAY 0.680851 (-8360 1510);
PAINT MONO (-8360 1510);
FORCEPROP 0 LASTPIN (-7900 1500) $PN 2
J 0
(-7890 1510);
DISPLAY 0.680851 (-7890 1510);
PAINT MONO (-7890 1510);
FORCEPROP 1 LAST CLS_PN G380-10015-01
J 0
(-8250 1700);
DISPLAY 1.212766 (-8250 1700);
PAINT GREEN (-8250 1700);
FORCEPROP 1 LAST LOCATION SP21
J 0
(-8250 1600);
DISPLAY 1.212766 (-8250 1600);
PAINT GREEN (-8250 1600);
FORCEPROP 1 LAST CDS_LMAN_SYM_OUTLINE 0,0,250,-200
J 0
(-8250 1600);
DISPLAY 0.468085 (-8250 1600);
PAINT GREEN (-8250 1600);
DISPLAY INVISIBLE (-8250 1600);
FORCEPROP 2 LAST CDS_LIB mech
J 0
(-8250 1600);
DISPLAY INVISIBLE (-8250 1600);
FORCEPROP 1 LAST PATH I150
J 0
(-8200 1650);
DISPLAY 1.212766 (-8200 1650);
PAINT GREEN (-8200 1650);
DISPLAY INVISIBLE (-8200 1650);
FORCEPROP 0 LAST $SEC 1
J 0
(-8250 1800);
DISPLAY 0.680851 (-8250 1800);
PAINT MONO (-8250 1800);
DISPLAY INVISIBLE (-8250 1800);
FORCEPROP 0 LAST CDS_SEC 1
J 0
(-8250 1800);
DISPLAY 1.021277 (-8250 1800);
DISPLAY INVISIBLE (-8250 1800);
FORCEADD SOLDER_PREFORM..1
(-10100 1600);
FORCEPROP 0 LASTPIN (-9750 1500) $PN 2
J 0
(-9740 1510);
DISPLAY 0.680851 (-9740 1510);
PAINT MONO (-9740 1510);
FORCEPROP 0 LASTPIN (-10200 1500) $PN 1
J 2
(-10210 1510);
DISPLAY 0.680851 (-10210 1510);
PAINT MONO (-10210 1510);
FORCEPROP 1 LAST CLS_PN G380-10015-01
J 0
(-10100 1700);
DISPLAY 1.212766 (-10100 1700);
PAINT GREEN (-10100 1700);
FORCEPROP 1 LAST LOCATION SP19
J 0
(-10100 1600);
DISPLAY 1.212766 (-10100 1600);
PAINT GREEN (-10100 1600);
FORCEPROP 1 LAST PATH I151
J 0
(-10050 1650);
DISPLAY 1.212766 (-10050 1650);
PAINT GREEN (-10050 1650);
DISPLAY INVISIBLE (-10050 1650);
FORCEPROP 1 LAST CDS_LMAN_SYM_OUTLINE 0,0,250,-200
J 0
(-10100 1600);
DISPLAY 0.468085 (-10100 1600);
PAINT GREEN (-10100 1600);
DISPLAY INVISIBLE (-10100 1600);
FORCEPROP 2 LAST CDS_LIB mech
J 0
(-10100 1600);
DISPLAY INVISIBLE (-10100 1600);
FORCEPROP 0 LAST $SEC 1
J 0
(-10100 1800);
DISPLAY 0.680851 (-10100 1800);
PAINT MONO (-10100 1800);
DISPLAY INVISIBLE (-10100 1800);
FORCEPROP 0 LAST CDS_SEC 1
J 0
(-10100 1800);
DISPLAY 1.021277 (-10100 1800);
DISPLAY INVISIBLE (-10100 1800);
FORCEADD SOLDER_PREFORM..1
(-11000 1600);
FORCEPROP 1 LAST LOCATION SP18
J 0
(-11000 1600);
DISPLAY 1.212766 (-11000 1600);
PAINT GREEN (-11000 1600);
FORCEPROP 0 LASTPIN (-11100 1500) $PN 1
J 2
(-11110 1510);
DISPLAY 0.680851 (-11110 1510);
PAINT MONO (-11110 1510);
FORCEPROP 0 LASTPIN (-10650 1500) $PN 2
J 0
(-10640 1510);
DISPLAY 0.680851 (-10640 1510);
PAINT MONO (-10640 1510);
FORCEPROP 1 LAST CLS_PN G380-10015-01
J 0
(-11000 1700);
DISPLAY 1.212766 (-11000 1700);
PAINT GREEN (-11000 1700);
FORCEPROP 2 LAST CDS_LIB mech
J 0
(-11000 1600);
DISPLAY INVISIBLE (-11000 1600);
FORCEPROP 1 LAST CDS_LMAN_SYM_OUTLINE 0,0,250,-200
J 0
(-11000 1600);
DISPLAY 0.468085 (-11000 1600);
PAINT GREEN (-11000 1600);
DISPLAY INVISIBLE (-11000 1600);
FORCEPROP 1 LAST PATH I152
J 0
(-10950 1650);
DISPLAY 1.212766 (-10950 1650);
PAINT GREEN (-10950 1650);
DISPLAY INVISIBLE (-10950 1650);
FORCEPROP 0 LAST $SEC 1
J 0
(-11000 1800);
DISPLAY 0.680851 (-11000 1800);
PAINT MONO (-11000 1800);
DISPLAY INVISIBLE (-11000 1800);
FORCEPROP 0 LAST CDS_SEC 1
J 0
(-11000 1800);
DISPLAY 1.021277 (-11000 1800);
DISPLAY INVISIBLE (-11000 1800);
FORCEADD SOLDER_PREFORM..1
(-12750 1600);
FORCEPROP 0 LASTPIN (-12850 1500) $PN 1
J 2
(-12860 1510);
DISPLAY 0.680851 (-12860 1510);
PAINT MONO (-12860 1510);
FORCEPROP 0 LASTPIN (-12400 1500) $PN 2
J 0
(-12390 1510);
DISPLAY 0.680851 (-12390 1510);
PAINT MONO (-12390 1510);
FORCEPROP 1 LAST LOCATION SP16
J 0
(-12750 1600);
DISPLAY 1.212766 (-12750 1600);
PAINT GREEN (-12750 1600);
FORCEPROP 1 LAST CLS_PN G380-10015-01
J 0
(-12750 1700);
DISPLAY 1.212766 (-12750 1700);
PAINT GREEN (-12750 1700);
FORCEPROP 1 LAST CDS_LMAN_SYM_OUTLINE 0,0,250,-200
J 0
(-12750 1600);
DISPLAY 0.468085 (-12750 1600);
PAINT GREEN (-12750 1600);
DISPLAY INVISIBLE (-12750 1600);
FORCEPROP 2 LAST CDS_LIB mech
J 0
(-12750 1600);
DISPLAY INVISIBLE (-12750 1600);
FORCEPROP 1 LAST PATH I153
J 0
(-12700 1650);
DISPLAY 1.212766 (-12700 1650);
PAINT GREEN (-12700 1650);
DISPLAY INVISIBLE (-12700 1650);
FORCEPROP 0 LAST $SEC 1
J 0
(-12750 1800);
DISPLAY 0.680851 (-12750 1800);
PAINT MONO (-12750 1800);
DISPLAY INVISIBLE (-12750 1800);
FORCEPROP 0 LAST CDS_SEC 1
J 0
(-12750 1800);
DISPLAY 1.021277 (-12750 1800);
DISPLAY INVISIBLE (-12750 1800);
FORCEADD SOLDER_PREFORM..1
(-11900 550);
FORCEPROP 1 LAST LOCATION SP41
J 0
(-11900 550);
DISPLAY 1.212766 (-11900 550);
PAINT GREEN (-11900 550);
FORCEPROP 0 LASTPIN (-12000 450) $PN 1
J 2
(-12010 460);
DISPLAY 0.680851 (-12010 460);
PAINT MONO (-12010 460);
FORCEPROP 0 LASTPIN (-11550 450) $PN 2
J 0
(-11540 460);
DISPLAY 0.680851 (-11540 460);
PAINT MONO (-11540 460);
FORCEPROP 1 LAST CLS_PN G380-10015-01
J 0
(-11900 650);
DISPLAY 1.212766 (-11900 650);
PAINT GREEN (-11900 650);
FORCEPROP 2 LAST CDS_LIB mech
J 0
(-11900 550);
DISPLAY INVISIBLE (-11900 550);
FORCEPROP 1 LAST CDS_LMAN_SYM_OUTLINE 0,0,250,-200
J 0
(-11900 550);
DISPLAY 0.468085 (-11900 550);
PAINT GREEN (-11900 550);
DISPLAY INVISIBLE (-11900 550);
FORCEPROP 1 LAST PATH I155
J 0
(-11850 600);
DISPLAY 1.212766 (-11850 600);
PAINT GREEN (-11850 600);
DISPLAY INVISIBLE (-11850 600);
FORCEPROP 0 LAST $SEC 1
J 0
(-11900 750);
DISPLAY 0.680851 (-11900 750);
PAINT MONO (-11900 750);
DISPLAY INVISIBLE (-11900 750);
FORCEPROP 0 LAST CDS_SEC 1
J 0
(-11900 750);
DISPLAY 1.021277 (-11900 750);
DISPLAY INVISIBLE (-11900 750);
FORCEADD SOLDER_PREFORM..1
(-3800 1100);
FORCEPROP 1 LAST LOCATION SP38
J 0
(-3800 1100);
DISPLAY 1.212766 (-3800 1100);
PAINT GREEN (-3800 1100);
FORCEPROP 1 LAST CLS_PN G380-10015-01
J 0
(-3800 1200);
DISPLAY 1.212766 (-3800 1200);
PAINT GREEN (-3800 1200);
FORCEPROP 0 LASTPIN (-3900 1000) $PN 1
J 2
(-3910 1010);
DISPLAY 0.680851 (-3910 1010);
PAINT MONO (-3910 1010);
FORCEPROP 0 LASTPIN (-3450 1000) $PN 2
J 0
(-3440 1010);
DISPLAY 0.680851 (-3440 1010);
PAINT MONO (-3440 1010);
FORCEPROP 2 LAST CDS_LIB mech
J 0
(-3800 1100);
DISPLAY INVISIBLE (-3800 1100);
FORCEPROP 1 LAST CDS_LMAN_SYM_OUTLINE 0,0,250,-200
J 0
(-3800 1100);
DISPLAY 0.468085 (-3800 1100);
PAINT GREEN (-3800 1100);
DISPLAY INVISIBLE (-3800 1100);
FORCEPROP 1 LAST PATH I159
J 0
(-3750 1150);
DISPLAY 1.212766 (-3750 1150);
PAINT GREEN (-3750 1150);
DISPLAY INVISIBLE (-3750 1150);
FORCEPROP 0 LAST $SEC 1
J 0
(-3800 1300);
DISPLAY 0.680851 (-3800 1300);
PAINT MONO (-3800 1300);
DISPLAY INVISIBLE (-3800 1300);
FORCEPROP 0 LAST CDS_SEC 1
J 0
(-3800 1300);
DISPLAY 1.021277 (-3800 1300);
DISPLAY INVISIBLE (-3800 1300);
FORCEADD SOLDER_PREFORM..1
(-4700 1100);
FORCEPROP 1 LAST LOCATION SP37
J 0
(-4700 1100);
DISPLAY 1.212766 (-4700 1100);
PAINT GREEN (-4700 1100);
FORCEPROP 1 LAST CLS_PN G380-10015-01
J 0
(-4700 1200);
DISPLAY 1.212766 (-4700 1200);
PAINT GREEN (-4700 1200);
FORCEPROP 0 LASTPIN (-4800 1000) $PN 1
J 2
(-4810 1010);
DISPLAY 0.680851 (-4810 1010);
PAINT MONO (-4810 1010);
FORCEPROP 0 LASTPIN (-4350 1000) $PN 2
J 0
(-4340 1010);
DISPLAY 0.680851 (-4340 1010);
PAINT MONO (-4340 1010);
FORCEPROP 2 LAST CDS_LIB mech
J 0
(-4700 1100);
DISPLAY INVISIBLE (-4700 1100);
FORCEPROP 1 LAST CDS_LMAN_SYM_OUTLINE 0,0,250,-200
J 0
(-4700 1100);
DISPLAY 0.468085 (-4700 1100);
PAINT GREEN (-4700 1100);
DISPLAY INVISIBLE (-4700 1100);
FORCEPROP 1 LAST PATH I161
J 0
(-4650 1150);
DISPLAY 1.212766 (-4650 1150);
PAINT GREEN (-4650 1150);
DISPLAY INVISIBLE (-4650 1150);
FORCEPROP 0 LAST $SEC 1
J 0
(-4700 1300);
DISPLAY 0.680851 (-4700 1300);
PAINT MONO (-4700 1300);
DISPLAY INVISIBLE (-4700 1300);
FORCEPROP 0 LAST CDS_SEC 1
J 0
(-4700 1300);
DISPLAY 1.021277 (-4700 1300);
DISPLAY INVISIBLE (-4700 1300);
FORCEADD SOLDER_PREFORM..1
(-5550 1100);
FORCEPROP 1 LAST LOCATION SP36
J 0
(-5550 1100);
DISPLAY 1.212766 (-5550 1100);
PAINT GREEN (-5550 1100);
FORCEPROP 0 LASTPIN (-5650 1000) $PN 1
J 2
(-5660 1010);
DISPLAY 0.680851 (-5660 1010);
PAINT MONO (-5660 1010);
FORCEPROP 0 LASTPIN (-5200 1000) $PN 2
J 0
(-5190 1010);
DISPLAY 0.680851 (-5190 1010);
PAINT MONO (-5190 1010);
FORCEPROP 1 LAST CLS_PN G380-10015-01
J 0
(-5550 1200);
DISPLAY 1.212766 (-5550 1200);
PAINT GREEN (-5550 1200);
FORCEPROP 1 LAST CDS_LMAN_SYM_OUTLINE 0,0,250,-200
J 0
(-5550 1100);
DISPLAY 0.468085 (-5550 1100);
PAINT GREEN (-5550 1100);
DISPLAY INVISIBLE (-5550 1100);
FORCEPROP 2 LAST CDS_LIB mech
J 0
(-5550 1100);
DISPLAY INVISIBLE (-5550 1100);
FORCEPROP 1 LAST PATH I163
J 0
(-5500 1150);
DISPLAY 1.212766 (-5500 1150);
PAINT GREEN (-5500 1150);
DISPLAY INVISIBLE (-5500 1150);
FORCEPROP 0 LAST $SEC 1
J 0
(-5550 1300);
DISPLAY 0.680851 (-5550 1300);
PAINT MONO (-5550 1300);
DISPLAY INVISIBLE (-5550 1300);
FORCEPROP 0 LAST CDS_SEC 1
J 0
(-5550 1300);
DISPLAY 1.021277 (-5550 1300);
DISPLAY INVISIBLE (-5550 1300);
FORCEADD SOLDER_PREFORM..1
(-6450 1100);
FORCEPROP 1 LAST LOCATION SP35
J 0
(-6450 1100);
DISPLAY 1.212766 (-6450 1100);
PAINT GREEN (-6450 1100);
FORCEPROP 0 LASTPIN (-6550 1000) $PN 1
J 2
(-6560 1010);
DISPLAY 0.680851 (-6560 1010);
PAINT MONO (-6560 1010);
FORCEPROP 0 LASTPIN (-6100 1000) $PN 2
J 0
(-6090 1010);
DISPLAY 0.680851 (-6090 1010);
PAINT MONO (-6090 1010);
FORCEPROP 1 LAST CLS_PN G380-10015-01
J 0
(-6450 1200);
DISPLAY 1.212766 (-6450 1200);
PAINT GREEN (-6450 1200);
FORCEPROP 1 LAST CDS_LMAN_SYM_OUTLINE 0,0,250,-200
J 0
(-6450 1100);
DISPLAY 0.468085 (-6450 1100);
PAINT GREEN (-6450 1100);
DISPLAY INVISIBLE (-6450 1100);
FORCEPROP 2 LAST CDS_LIB mech
J 0
(-6450 1100);
DISPLAY INVISIBLE (-6450 1100);
FORCEPROP 1 LAST PATH I165
J 0
(-6400 1150);
DISPLAY 1.212766 (-6400 1150);
PAINT GREEN (-6400 1150);
DISPLAY INVISIBLE (-6400 1150);
FORCEPROP 0 LAST $SEC 1
J 0
(-6450 1300);
DISPLAY 0.680851 (-6450 1300);
PAINT MONO (-6450 1300);
DISPLAY INVISIBLE (-6450 1300);
FORCEPROP 0 LAST CDS_SEC 1
J 0
(-6450 1300);
DISPLAY 1.021277 (-6450 1300);
DISPLAY INVISIBLE (-6450 1300);
FORCEADD SOLDER_PREFORM..1
(-7400 1100);
FORCEPROP 1 LAST LOCATION SP34
J 0
(-7400 1100);
DISPLAY 1.212766 (-7400 1100);
PAINT GREEN (-7400 1100);
FORCEPROP 0 LASTPIN (-7500 1000) $PN 1
J 2
(-7510 1010);
DISPLAY 0.680851 (-7510 1010);
PAINT MONO (-7510 1010);
FORCEPROP 0 LASTPIN (-7050 1000) $PN 2
J 0
(-7040 1010);
DISPLAY 0.680851 (-7040 1010);
PAINT MONO (-7040 1010);
FORCEPROP 1 LAST CLS_PN G380-10015-01
J 0
(-7400 1200);
DISPLAY 1.212766 (-7400 1200);
PAINT GREEN (-7400 1200);
FORCEPROP 2 LAST CDS_LIB mech
J 0
(-7400 1100);
DISPLAY INVISIBLE (-7400 1100);
FORCEPROP 1 LAST CDS_LMAN_SYM_OUTLINE 0,0,250,-200
J 0
(-7400 1100);
DISPLAY 0.468085 (-7400 1100);
PAINT GREEN (-7400 1100);
DISPLAY INVISIBLE (-7400 1100);
FORCEPROP 1 LAST PATH I167
J 0
(-7350 1150);
DISPLAY 1.212766 (-7350 1150);
PAINT GREEN (-7350 1150);
DISPLAY INVISIBLE (-7350 1150);
FORCEPROP 0 LAST $SEC 1
J 0
(-7400 1300);
DISPLAY 0.680851 (-7400 1300);
PAINT MONO (-7400 1300);
DISPLAY INVISIBLE (-7400 1300);
FORCEPROP 0 LAST CDS_SEC 1
J 0
(-7400 1300);
DISPLAY 1.021277 (-7400 1300);
DISPLAY INVISIBLE (-7400 1300);
FORCEADD SOLDER_PREFORM..1
(-8300 1100);
FORCEPROP 1 LAST LOCATION SP33
J 0
(-8300 1100);
DISPLAY 1.212766 (-8300 1100);
PAINT GREEN (-8300 1100);
FORCEPROP 1 LAST CLS_PN G380-10015-01
J 0
(-8300 1200);
DISPLAY 1.212766 (-8300 1200);
PAINT GREEN (-8300 1200);
FORCEPROP 0 LASTPIN (-8400 1000) $PN 1
J 2
(-8410 1010);
DISPLAY 0.680851 (-8410 1010);
PAINT MONO (-8410 1010);
FORCEPROP 0 LASTPIN (-7950 1000) $PN 2
J 0
(-7940 1010);
DISPLAY 0.680851 (-7940 1010);
PAINT MONO (-7940 1010);
FORCEPROP 2 LAST CDS_LIB mech
J 0
(-8300 1100);
DISPLAY INVISIBLE (-8300 1100);
FORCEPROP 1 LAST CDS_LMAN_SYM_OUTLINE 0,0,250,-200
J 0
(-8300 1100);
DISPLAY 0.468085 (-8300 1100);
PAINT GREEN (-8300 1100);
DISPLAY INVISIBLE (-8300 1100);
FORCEPROP 1 LAST PATH I169
J 0
(-8250 1150);
DISPLAY 1.212766 (-8250 1150);
PAINT GREEN (-8250 1150);
DISPLAY INVISIBLE (-8250 1150);
FORCEPROP 0 LAST $SEC 1
J 0
(-8300 1300);
DISPLAY 0.680851 (-8300 1300);
PAINT MONO (-8300 1300);
DISPLAY INVISIBLE (-8300 1300);
FORCEPROP 0 LAST CDS_SEC 1
J 0
(-8300 1300);
DISPLAY 1.021277 (-8300 1300);
DISPLAY INVISIBLE (-8300 1300);
FORCEADD SOLDER_PREFORM..1
(-9150 1100);
FORCEPROP 1 LAST LOCATION SP32
J 0
(-9150 1100);
DISPLAY 1.212766 (-9150 1100);
PAINT GREEN (-9150 1100);
FORCEPROP 0 LASTPIN (-9250 1000) $PN 1
J 2
(-9260 1010);
DISPLAY 0.680851 (-9260 1010);
PAINT MONO (-9260 1010);
FORCEPROP 0 LASTPIN (-8800 1000) $PN 2
J 0
(-8790 1010);
DISPLAY 0.680851 (-8790 1010);
PAINT MONO (-8790 1010);
FORCEPROP 1 LAST CLS_PN G380-10015-01
J 0
(-9150 1200);
DISPLAY 1.212766 (-9150 1200);
PAINT GREEN (-9150 1200);
FORCEPROP 1 LAST CDS_LMAN_SYM_OUTLINE 0,0,250,-200
J 0
(-9150 1100);
DISPLAY 0.468085 (-9150 1100);
PAINT GREEN (-9150 1100);
DISPLAY INVISIBLE (-9150 1100);
FORCEPROP 2 LAST CDS_LIB mech
J 0
(-9150 1100);
DISPLAY INVISIBLE (-9150 1100);
FORCEPROP 1 LAST PATH I171
J 0
(-9100 1150);
DISPLAY 1.212766 (-9100 1150);
PAINT GREEN (-9100 1150);
DISPLAY INVISIBLE (-9100 1150);
FORCEPROP 0 LAST $SEC 1
J 0
(-9150 1300);
DISPLAY 0.680851 (-9150 1300);
PAINT MONO (-9150 1300);
DISPLAY INVISIBLE (-9150 1300);
FORCEPROP 0 LAST CDS_SEC 1
J 0
(-9150 1300);
DISPLAY 1.021277 (-9150 1300);
DISPLAY INVISIBLE (-9150 1300);
FORCEADD SOLDER_PREFORM..1
(-10050 1100);
FORCEPROP 1 LAST LOCATION SP31
J 0
(-10050 1100);
DISPLAY 1.212766 (-10050 1100);
PAINT GREEN (-10050 1100);
FORCEPROP 0 LASTPIN (-10150 1000) $PN 1
J 2
(-10160 1010);
DISPLAY 0.680851 (-10160 1010);
PAINT MONO (-10160 1010);
FORCEPROP 0 LASTPIN (-9700 1000) $PN 2
J 0
(-9690 1010);
DISPLAY 0.680851 (-9690 1010);
PAINT MONO (-9690 1010);
FORCEPROP 1 LAST CLS_PN G380-10015-01
J 0
(-10050 1200);
DISPLAY 1.212766 (-10050 1200);
PAINT GREEN (-10050 1200);
FORCEPROP 1 LAST CDS_LMAN_SYM_OUTLINE 0,0,250,-200
J 0
(-10050 1100);
DISPLAY 0.468085 (-10050 1100);
PAINT GREEN (-10050 1100);
DISPLAY INVISIBLE (-10050 1100);
FORCEPROP 2 LAST CDS_LIB mech
J 0
(-10050 1100);
DISPLAY INVISIBLE (-10050 1100);
FORCEPROP 1 LAST PATH I172
J 0
(-10000 1150);
DISPLAY 1.212766 (-10000 1150);
PAINT GREEN (-10000 1150);
DISPLAY INVISIBLE (-10000 1150);
FORCEPROP 0 LAST $SEC 1
J 0
(-10050 1300);
DISPLAY 0.680851 (-10050 1300);
PAINT MONO (-10050 1300);
DISPLAY INVISIBLE (-10050 1300);
FORCEPROP 0 LAST CDS_SEC 1
J 0
(-10050 1300);
DISPLAY 1.021277 (-10050 1300);
DISPLAY INVISIBLE (-10050 1300);
FORCEADD SOLDER_PREFORM..1
(-11000 1100);
FORCEPROP 0 LASTPIN (-11100 1000) $PN 1
J 2
(-11110 1010);
DISPLAY 0.680851 (-11110 1010);
PAINT MONO (-11110 1010);
FORCEPROP 1 LAST LOCATION SP30
J 0
(-11000 1100);
DISPLAY 1.212766 (-11000 1100);
PAINT GREEN (-11000 1100);
FORCEPROP 0 LASTPIN (-10650 1000) $PN 2
J 0
(-10640 1010);
DISPLAY 0.680851 (-10640 1010);
PAINT MONO (-10640 1010);
FORCEPROP 1 LAST CLS_PN G380-10015-01
J 0
(-11000 1200);
DISPLAY 1.212766 (-11000 1200);
PAINT GREEN (-11000 1200);
FORCEPROP 2 LAST CDS_LIB mech
J 0
(-11000 1100);
DISPLAY INVISIBLE (-11000 1100);
FORCEPROP 1 LAST CDS_LMAN_SYM_OUTLINE 0,0,250,-200
J 0
(-11000 1100);
DISPLAY 0.468085 (-11000 1100);
PAINT GREEN (-11000 1100);
DISPLAY INVISIBLE (-11000 1100);
FORCEPROP 1 LAST PATH I173
J 0
(-10950 1150);
DISPLAY 1.212766 (-10950 1150);
PAINT GREEN (-10950 1150);
DISPLAY INVISIBLE (-10950 1150);
FORCEPROP 0 LAST $SEC 1
J 0
(-11000 1300);
DISPLAY 0.680851 (-11000 1300);
PAINT MONO (-11000 1300);
DISPLAY INVISIBLE (-11000 1300);
FORCEPROP 0 LAST CDS_SEC 1
J 0
(-11000 1300);
DISPLAY 1.021277 (-11000 1300);
DISPLAY INVISIBLE (-11000 1300);
FORCEADD SOLDER_PREFORM..1
(-11900 1100);
FORCEPROP 0 LASTPIN (-11550 1000) $PN 2
J 0
(-11540 1010);
DISPLAY 0.680851 (-11540 1010);
PAINT MONO (-11540 1010);
FORCEPROP 0 LASTPIN (-12000 1000) $PN 1
J 2
(-12010 1010);
DISPLAY 0.680851 (-12010 1010);
PAINT MONO (-12010 1010);
FORCEPROP 1 LAST CLS_PN G380-10015-01
J 0
(-11900 1200);
DISPLAY 1.212766 (-11900 1200);
PAINT GREEN (-11900 1200);
FORCEPROP 1 LAST LOCATION SP29
J 0
(-11900 1100);
DISPLAY 1.212766 (-11900 1100);
PAINT GREEN (-11900 1100);
FORCEPROP 2 LAST CDS_LIB mech
J 0
(-11900 1100);
DISPLAY INVISIBLE (-11900 1100);
FORCEPROP 1 LAST CDS_LMAN_SYM_OUTLINE 0,0,250,-200
J 0
(-11900 1100);
DISPLAY 0.468085 (-11900 1100);
PAINT GREEN (-11900 1100);
DISPLAY INVISIBLE (-11900 1100);
FORCEPROP 1 LAST PATH I174
J 0
(-11850 1150);
DISPLAY 1.212766 (-11850 1150);
PAINT GREEN (-11850 1150);
DISPLAY INVISIBLE (-11850 1150);
FORCEPROP 0 LAST $SEC 1
J 0
(-11900 1300);
DISPLAY 0.680851 (-11900 1300);
PAINT MONO (-11900 1300);
DISPLAY INVISIBLE (-11900 1300);
FORCEPROP 0 LAST CDS_SEC 1
J 0
(-11900 1300);
DISPLAY 1.021277 (-11900 1300);
DISPLAY INVISIBLE (-11900 1300);
FORCEADD SOLDER_PREFORM..1
(-12750 1100);
FORCEPROP 1 LAST LOCATION SP28
J 0
(-12750 1100);
DISPLAY 1.212766 (-12750 1100);
PAINT GREEN (-12750 1100);
FORCEPROP 0 LASTPIN (-12850 1000) $PN 1
J 2
(-12860 1010);
DISPLAY 0.680851 (-12860 1010);
PAINT MONO (-12860 1010);
FORCEPROP 0 LASTPIN (-12400 1000) $PN 2
J 0
(-12390 1010);
DISPLAY 0.680851 (-12390 1010);
PAINT MONO (-12390 1010);
FORCEPROP 1 LAST CLS_PN G380-10015-01
J 0
(-12750 1200);
DISPLAY 1.212766 (-12750 1200);
PAINT GREEN (-12750 1200);
FORCEPROP 1 LAST CDS_LMAN_SYM_OUTLINE 0,0,250,-200
J 0
(-12750 1100);
DISPLAY 0.468085 (-12750 1100);
PAINT GREEN (-12750 1100);
DISPLAY INVISIBLE (-12750 1100);
FORCEPROP 2 LAST CDS_LIB mech
J 0
(-12750 1100);
DISPLAY INVISIBLE (-12750 1100);
FORCEPROP 1 LAST PATH I175
J 0
(-12700 1150);
DISPLAY 1.212766 (-12700 1150);
PAINT GREEN (-12700 1150);
DISPLAY INVISIBLE (-12700 1150);
FORCEPROP 0 LAST $SEC 1
J 0
(-12750 1300);
DISPLAY 0.680851 (-12750 1300);
PAINT MONO (-12750 1300);
DISPLAY INVISIBLE (-12750 1300);
FORCEPROP 0 LAST CDS_SEC 1
J 0
(-12750 1300);
DISPLAY 1.021277 (-12750 1300);
DISPLAY INVISIBLE (-12750 1300);
FORCEADD SOLDER_PREFORM..1
(-12750 550);
FORCEPROP 0 LASTPIN (-12400 450) $PN 2
J 0
(-12390 460);
DISPLAY 0.680851 (-12390 460);
PAINT MONO (-12390 460);
FORCEPROP 1 LAST CLS_PN G380-10015-01
J 0
(-12750 650);
DISPLAY 1.212766 (-12750 650);
PAINT GREEN (-12750 650);
FORCEPROP 0 LASTPIN (-12850 450) $PN 1
J 2
(-12860 460);
DISPLAY 0.680851 (-12860 460);
PAINT MONO (-12860 460);
FORCEPROP 1 LAST LOCATION SP40
J 0
(-12750 550);
DISPLAY 1.212766 (-12750 550);
PAINT GREEN (-12750 550);
FORCEPROP 1 LAST CDS_LMAN_SYM_OUTLINE 0,0,250,-200
J 0
(-12750 550);
DISPLAY 0.468085 (-12750 550);
PAINT GREEN (-12750 550);
DISPLAY INVISIBLE (-12750 550);
FORCEPROP 2 LAST CDS_LIB mech
J 0
(-12750 550);
DISPLAY INVISIBLE (-12750 550);
FORCEPROP 1 LAST PATH I176
J 0
(-12700 600);
DISPLAY 1.212766 (-12700 600);
PAINT GREEN (-12700 600);
DISPLAY INVISIBLE (-12700 600);
FORCEPROP 0 LAST $SEC 1
J 0
(-12750 750);
DISPLAY 0.680851 (-12750 750);
PAINT MONO (-12750 750);
DISPLAY INVISIBLE (-12750 750);
FORCEPROP 0 LAST CDS_SEC 1
J 0
(-12750 750);
DISPLAY 1.021277 (-12750 750);
DISPLAY INVISIBLE (-12750 750);
FORCEADD SOLDER_PREFORM..1
(-2900 1100);
FORCEPROP 1 LAST LOCATION SP39
J 0
(-2900 1100);
DISPLAY 1.212766 (-2900 1100);
PAINT GREEN (-2900 1100);
FORCEPROP 1 LAST CLS_PN G380-10015-01
J 0
(-2900 1200);
DISPLAY 1.212766 (-2900 1200);
PAINT GREEN (-2900 1200);
FORCEPROP 0 LASTPIN (-3000 1000) $PN 1
J 2
(-3010 1010);
DISPLAY 0.680851 (-3010 1010);
PAINT MONO (-3010 1010);
FORCEPROP 0 LASTPIN (-2550 1000) $PN 2
J 0
(-2540 1010);
DISPLAY 0.680851 (-2540 1010);
PAINT MONO (-2540 1010);
FORCEPROP 1 LAST CDS_LMAN_SYM_OUTLINE 0,0,250,-200
J 0
(-2900 1100);
DISPLAY 0.468085 (-2900 1100);
PAINT GREEN (-2900 1100);
DISPLAY INVISIBLE (-2900 1100);
FORCEPROP 2 LAST CDS_LIB mech
J 0
(-2900 1100);
DISPLAY INVISIBLE (-2900 1100);
FORCEPROP 1 LAST PATH I177
J 0
(-2850 1150);
DISPLAY 1.212766 (-2850 1150);
PAINT GREEN (-2850 1150);
DISPLAY INVISIBLE (-2850 1150);
FORCEPROP 0 LAST $SEC 1
J 0
(-2900 1300);
DISPLAY 0.680851 (-2900 1300);
PAINT MONO (-2900 1300);
DISPLAY INVISIBLE (-2900 1300);
FORCEPROP 0 LAST CDS_SEC 1
J 0
(-2900 1300);
DISPLAY 1.021277 (-2900 1300);
DISPLAY INVISIBLE (-2900 1300);
FORCEADD MEC_MTH8..1
(-1850 6550);
FORCEPROP 0 LASTPIN (-1950 6100) $PN 5
J 2
(-1960 6110);
DISPLAY 0.680851 (-1960 6110);
PAINT MONO (-1960 6110);
FORCEPROP 0 LASTPIN (-1950 6000) $PN 6
J 2
(-1960 6010);
DISPLAY 0.680851 (-1960 6010);
PAINT MONO (-1960 6010);
FORCEPROP 0 LASTPIN (-1950 5900) $PN 7
J 2
(-1960 5910);
DISPLAY 0.680851 (-1960 5910);
PAINT MONO (-1960 5910);
FORCEPROP 0 LASTPIN (-1950 5800) $PN 8
J 2
(-1960 5810);
DISPLAY 0.680851 (-1960 5810);
PAINT MONO (-1960 5810);
FORCEPROP 0 LASTPIN (-1950 6200) $PN 4
J 2
(-1960 6210);
DISPLAY 0.680851 (-1960 6210);
PAINT MONO (-1960 6210);
FORCEPROP 0 LASTPIN (-1950 6300) $PN 3
J 2
(-1960 6310);
DISPLAY 0.680851 (-1960 6310);
PAINT MONO (-1960 6310);
FORCEPROP 0 LASTPIN (-1950 6500) $PN 1
J 2
(-1960 6510);
DISPLAY 0.680851 (-1960 6510);
PAINT MONO (-1960 6510);
FORCEPROP 0 LASTPIN (-1950 6400) $PN 2
J 2
(-1960 6410);
DISPLAY 0.680851 (-1960 6410);
PAINT MONO (-1960 6410);
FORCEPROP 1 LAST $LOCATION ME12
J 0
(-1851 6600);
DISPLAY 0.808511 (-1851 6600);
PAINT GREEN (-1851 6600);
FORCEPROP 0 LAST CDS_SEC 1
J 0
(-1850 6650);
DISPLAY 1.021277 (-1850 6650);
DISPLAY INVISIBLE (-1850 6650);
FORCEPROP 0 LAST $SEC 1
J 0
(-1850 6650);
DISPLAY 0.680851 (-1850 6650);
PAINT MONO (-1850 6650);
DISPLAY INVISIBLE (-1850 6650);
FORCEPROP 0 LAST CDS_LOCATION ME12
J 0
(-1850 6650);
DISPLAY 1.021277 (-1850 6650);
DISPLAY INVISIBLE (-1850 6650);
FORCEPROP 2 LAST CDS_LIB mech
J 0
(-1850 6550);
DISPLAY INVISIBLE (-1850 6550);
FORCEPROP 1 LAST CDS_LMAN_SYM_OUTLINE 0,0,100,-800
J 0
(-1850 6550);
DISPLAY 0.468085 (-1850 6550);
PAINT GREEN (-1850 6550);
DISPLAY INVISIBLE (-1850 6550);
FORCEPROP 1 LAST JEDEC_TYPE MTH125C236N_V8
J 0
(-1924 6600);
DISPLAY 0.000000 (-1924 6600);
PAINT GREEN (-1924 6600);
DISPLAY INVISIBLE (-1924 6600);
FORCEPROP 1 LAST BOM_IGNORE TRUE
J 0
(-1924 6600);
DISPLAY 0.000000 (-1924 6600);
PAINT GREEN (-1924 6600);
DISPLAY INVISIBLE (-1924 6600);
FORCEPROP 1 LAST PATH I2
J 0
(-1720 6613);
DISPLAY 0.808511 (-1720 6613);
PAINT GREEN (-1720 6613);
DISPLAY INVISIBLE (-1720 6613);
FORCEADD GND_SG..1
(-2200 5650);
FORCEPROP 3 LASTPIN (-2150 5700) SIG_NAME SG\g
J 0
(-2140 5710);
DISPLAY 0.659574 (-2140 5710);
PAINT MONO (-2140 5710);
DISPLAY INVISIBLE (-2140 5710);
FORCEPROP 1 LAST HDL_POWER SG
J 1
(-2145 5555);
DISPLAY 0.808511 (-2145 5555);
PAINT GREEN (-2145 5555);
FORCEPROP 1 LAST PATH I3
J 0
(-2165 5650);
DISPLAY 0.808511 (-2165 5650);
PAINT GREEN (-2165 5650);
DISPLAY INVISIBLE (-2165 5650);
FORCEPROP 1 LAST BODY_TYPE PLUMBING
J 0
(-2185 5635);
DISPLAY 0.808511 (-2185 5635);
PAINT GREEN (-2185 5635);
DISPLAY INVISIBLE (-2185 5635);
FORCEPROP 2 LAST CDS_LIB cls
J 0
(-2200 5650);
DISPLAY INVISIBLE (-2200 5650);
FORCEPROP 1 LAST CDS_LMAN_SYM_OUTLINE 0,0,100,-50
J 0
(-2200 5650);
DISPLAY 0.468085 (-2200 5650);
PAINT GREEN (-2200 5650);
DISPLAY INVISIBLE (-2200 5650);
FORCEADD GND_SG..1
(-3750 5650);
FORCEPROP 3 LASTPIN (-3700 5700) SIG_NAME SG\g
J 0
(-3690 5710);
DISPLAY 0.659574 (-3690 5710);
PAINT MONO (-3690 5710);
DISPLAY INVISIBLE (-3690 5710);
FORCEPROP 1 LAST HDL_POWER SG
J 1
(-3695 5555);
DISPLAY 0.808511 (-3695 5555);
PAINT GREEN (-3695 5555);
FORCEPROP 1 LAST PATH I4
J 0
(-3715 5650);
DISPLAY 0.808511 (-3715 5650);
PAINT GREEN (-3715 5650);
DISPLAY INVISIBLE (-3715 5650);
FORCEPROP 1 LAST BODY_TYPE PLUMBING
J 0
(-3735 5635);
DISPLAY 0.808511 (-3735 5635);
PAINT GREEN (-3735 5635);
DISPLAY INVISIBLE (-3735 5635);
FORCEPROP 1 LAST CDS_LMAN_SYM_OUTLINE 0,0,100,-50
J 0
(-3750 5650);
DISPLAY 0.468085 (-3750 5650);
PAINT GREEN (-3750 5650);
DISPLAY INVISIBLE (-3750 5650);
FORCEPROP 2 LAST CDS_LIB cls
J 0
(-3750 5650);
DISPLAY INVISIBLE (-3750 5650);
FORCEADD NULL..1
(-12750 3850);
FORCEPROP 1 LAST LOCATION SP54
J 0
(-12750 3900);
DISPLAY 1.212766 (-12750 3900);
PAINT GREEN (-12750 3900);
FORCEPROP 1 LAST CLS_PN G380-10013-01
J 0
(-12750 4000);
DISPLAY 1.212766 (-12750 4000);
PAINT GREEN (-12750 4000);
FORCEPROP 1 LAST PATH I47
J 0
(-12700 3900);
DISPLAY 1.212766 (-12700 3900);
PAINT GREEN (-12700 3900);
DISPLAY INVISIBLE (-12700 3900);
FORCEPROP 2 LAST CDS_LIB mech
J 0
(-12750 3850);
DISPLAY INVISIBLE (-12750 3850);
FORCEPROP 1 LAST CDS_LMAN_SYM_OUTLINE 0,0,300,-300
J 0
(-12750 3850);
DISPLAY 0.468085 (-12750 3850);
PAINT GREEN (-12750 3850);
DISPLAY INVISIBLE (-12750 3850);
FORCEADD NULL..1
(-11800 3850);
FORCEPROP 1 LAST CLS_PN G380-10013-01
J 0
(-11800 4000);
DISPLAY 1.212766 (-11800 4000);
PAINT GREEN (-11800 4000);
FORCEPROP 1 LAST LOCATION SP55
J 0
(-11800 3900);
DISPLAY 1.212766 (-11800 3900);
PAINT GREEN (-11800 3900);
FORCEPROP 1 LAST PATH I48
J 0
(-11750 3900);
DISPLAY 1.212766 (-11750 3900);
PAINT GREEN (-11750 3900);
DISPLAY INVISIBLE (-11750 3900);
FORCEPROP 2 LAST CDS_LIB mech
J 0
(-11800 3850);
DISPLAY INVISIBLE (-11800 3850);
FORCEPROP 1 LAST CDS_LMAN_SYM_OUTLINE 0,0,300,-300
J 0
(-11800 3850);
DISPLAY 0.468085 (-11800 3850);
PAINT GREEN (-11800 3850);
DISPLAY INVISIBLE (-11800 3850);
FORCEADD NULL..1
(-9900 3850);
FORCEPROP 1 LAST CLS_PN G380-10013-01
J 0
(-9900 4000);
DISPLAY 1.212766 (-9900 4000);
PAINT GREEN (-9900 4000);
FORCEPROP 1 LAST LOCATION SP57
J 0
(-9900 3900);
DISPLAY 1.212766 (-9900 3900);
PAINT GREEN (-9900 3900);
FORCEPROP 1 LAST PATH I49
J 0
(-9850 3900);
DISPLAY 1.212766 (-9850 3900);
PAINT GREEN (-9850 3900);
DISPLAY INVISIBLE (-9850 3900);
FORCEPROP 2 LAST CDS_LIB mech
J 0
(-9900 3850);
DISPLAY INVISIBLE (-9900 3850);
FORCEPROP 1 LAST CDS_LMAN_SYM_OUTLINE 0,0,300,-300
J 0
(-9900 3850);
DISPLAY 0.468085 (-9900 3850);
PAINT GREEN (-9900 3850);
DISPLAY INVISIBLE (-9900 3850);
FORCEADD MEC_MTH8..1
(-4950 6550);
FORCEPROP 0 LASTPIN (-5050 6100) $PN 5
J 2
(-5060 6110);
DISPLAY 0.680851 (-5060 6110);
PAINT MONO (-5060 6110);
FORCEPROP 0 LASTPIN (-5050 6000) $PN 6
J 2
(-5060 6010);
DISPLAY 0.680851 (-5060 6010);
PAINT MONO (-5060 6010);
FORCEPROP 0 LASTPIN (-5050 5900) $PN 7
J 2
(-5060 5910);
DISPLAY 0.680851 (-5060 5910);
PAINT MONO (-5060 5910);
FORCEPROP 0 LASTPIN (-5050 5800) $PN 8
J 2
(-5060 5810);
DISPLAY 0.680851 (-5060 5810);
PAINT MONO (-5060 5810);
FORCEPROP 0 LASTPIN (-5050 6200) $PN 4
J 2
(-5060 6210);
DISPLAY 0.680851 (-5060 6210);
PAINT MONO (-5060 6210);
FORCEPROP 0 LASTPIN (-5050 6300) $PN 3
J 2
(-5060 6310);
DISPLAY 0.680851 (-5060 6310);
PAINT MONO (-5060 6310);
FORCEPROP 0 LASTPIN (-5050 6500) $PN 1
J 2
(-5060 6510);
DISPLAY 0.680851 (-5060 6510);
PAINT MONO (-5060 6510);
FORCEPROP 0 LASTPIN (-5050 6400) $PN 2
J 2
(-5060 6410);
DISPLAY 0.680851 (-5060 6410);
PAINT MONO (-5060 6410);
FORCEPROP 1 LAST $LOCATION ME10
J 0
(-4951 6600);
DISPLAY 0.808511 (-4951 6600);
PAINT GREEN (-4951 6600);
FORCEPROP 0 LAST CDS_SEC 1
J 0
(-4950 6650);
DISPLAY 1.021277 (-4950 6650);
DISPLAY INVISIBLE (-4950 6650);
FORCEPROP 0 LAST $SEC 1
J 0
(-4950 6650);
DISPLAY 0.680851 (-4950 6650);
PAINT MONO (-4950 6650);
DISPLAY INVISIBLE (-4950 6650);
FORCEPROP 0 LAST CDS_LOCATION ME10
J 0
(-4950 6650);
DISPLAY 1.021277 (-4950 6650);
DISPLAY INVISIBLE (-4950 6650);
FORCEPROP 2 LAST CDS_LIB mech
J 0
(-4950 6550);
DISPLAY INVISIBLE (-4950 6550);
FORCEPROP 1 LAST CDS_LMAN_SYM_OUTLINE 0,0,100,-800
J 0
(-4950 6550);
DISPLAY 0.468085 (-4950 6550);
PAINT GREEN (-4950 6550);
DISPLAY INVISIBLE (-4950 6550);
FORCEPROP 1 LAST JEDEC_TYPE MTH125C236N_V8
J 0
(-5024 6600);
DISPLAY 0.000000 (-5024 6600);
PAINT GREEN (-5024 6600);
DISPLAY INVISIBLE (-5024 6600);
FORCEPROP 1 LAST BOM_IGNORE TRUE
J 0
(-5024 6600);
DISPLAY 0.000000 (-5024 6600);
PAINT GREEN (-5024 6600);
DISPLAY INVISIBLE (-5024 6600);
FORCEPROP 1 LAST PATH I5
J 0
(-4820 6613);
DISPLAY 0.808511 (-4820 6613);
PAINT GREEN (-4820 6613);
DISPLAY INVISIBLE (-4820 6613);
FORCEADD NULL..1
(-10850 3850);
FORCEPROP 1 LAST LOCATION SP56
J 0
(-10850 3900);
DISPLAY 1.212766 (-10850 3900);
PAINT GREEN (-10850 3900);
FORCEPROP 1 LAST CLS_PN G380-10013-01
J 0
(-10850 4000);
DISPLAY 1.212766 (-10850 4000);
PAINT GREEN (-10850 4000);
FORCEPROP 1 LAST PATH I50
J 0
(-10800 3900);
DISPLAY 1.212766 (-10800 3900);
PAINT GREEN (-10800 3900);
DISPLAY INVISIBLE (-10800 3900);
FORCEPROP 2 LAST CDS_LIB mech
J 0
(-10850 3850);
DISPLAY INVISIBLE (-10850 3850);
FORCEPROP 1 LAST CDS_LMAN_SYM_OUTLINE 0,0,300,-300
J 0
(-10850 3850);
DISPLAY 0.468085 (-10850 3850);
PAINT GREEN (-10850 3850);
DISPLAY INVISIBLE (-10850 3850);
FORCEADD NULL..1
(-6100 3850);
FORCEPROP 1 LAST CLS_PN G380-10013-01
J 0
(-6100 4000);
DISPLAY 1.212766 (-6100 4000);
PAINT GREEN (-6100 4000);
FORCEPROP 1 LAST LOCATION SP61
J 0
(-6100 3900);
DISPLAY 1.212766 (-6100 3900);
PAINT GREEN (-6100 3900);
FORCEPROP 1 LAST PATH I51
J 0
(-6050 3900);
DISPLAY 1.212766 (-6050 3900);
PAINT GREEN (-6050 3900);
DISPLAY INVISIBLE (-6050 3900);
FORCEPROP 2 LAST CDS_LIB mech
J 0
(-6100 3850);
DISPLAY INVISIBLE (-6100 3850);
FORCEPROP 1 LAST CDS_LMAN_SYM_OUTLINE 0,0,300,-300
J 0
(-6100 3850);
DISPLAY 0.468085 (-6100 3850);
PAINT GREEN (-6100 3850);
DISPLAY INVISIBLE (-6100 3850);
FORCEADD NULL..1
(-7050 3850);
FORCEPROP 1 LAST LOCATION SP60
J 0
(-7050 3900);
DISPLAY 1.212766 (-7050 3900);
PAINT GREEN (-7050 3900);
FORCEPROP 1 LAST CLS_PN G380-10013-01
J 0
(-7050 4000);
DISPLAY 1.212766 (-7050 4000);
PAINT GREEN (-7050 4000);
FORCEPROP 1 LAST PATH I52
J 0
(-7000 3900);
DISPLAY 1.212766 (-7000 3900);
PAINT GREEN (-7000 3900);
DISPLAY INVISIBLE (-7000 3900);
FORCEPROP 2 LAST CDS_LIB mech
J 0
(-7050 3850);
DISPLAY INVISIBLE (-7050 3850);
FORCEPROP 1 LAST CDS_LMAN_SYM_OUTLINE 0,0,300,-300
J 0
(-7050 3850);
DISPLAY 0.468085 (-7050 3850);
PAINT GREEN (-7050 3850);
DISPLAY INVISIBLE (-7050 3850);
FORCEADD NULL..1
(-8000 3850);
FORCEPROP 1 LAST CLS_PN G380-10013-01
J 0
(-8000 4000);
DISPLAY 1.212766 (-8000 4000);
PAINT GREEN (-8000 4000);
FORCEPROP 1 LAST LOCATION SP59
J 0
(-8000 3900);
DISPLAY 1.212766 (-8000 3900);
PAINT GREEN (-8000 3900);
FORCEPROP 1 LAST PATH I53
J 0
(-7950 3900);
DISPLAY 1.212766 (-7950 3900);
PAINT GREEN (-7950 3900);
DISPLAY INVISIBLE (-7950 3900);
FORCEPROP 2 LAST CDS_LIB mech
J 0
(-8000 3850);
DISPLAY INVISIBLE (-8000 3850);
FORCEPROP 1 LAST CDS_LMAN_SYM_OUTLINE 0,0,300,-300
J 0
(-8000 3850);
DISPLAY 0.468085 (-8000 3850);
PAINT GREEN (-8000 3850);
DISPLAY INVISIBLE (-8000 3850);
FORCEADD NULL..1
(-8950 3850);
FORCEPROP 1 LAST LOCATION SP58
J 0
(-8950 3900);
DISPLAY 1.212766 (-8950 3900);
PAINT GREEN (-8950 3900);
FORCEPROP 1 LAST CLS_PN G380-10013-01
J 0
(-8950 4000);
DISPLAY 1.212766 (-8950 4000);
PAINT GREEN (-8950 4000);
FORCEPROP 1 LAST PATH I54
J 0
(-8900 3900);
DISPLAY 1.212766 (-8900 3900);
PAINT GREEN (-8900 3900);
DISPLAY INVISIBLE (-8900 3900);
FORCEPROP 2 LAST CDS_LIB mech
J 0
(-8950 3850);
DISPLAY INVISIBLE (-8950 3850);
FORCEPROP 1 LAST CDS_LMAN_SYM_OUTLINE 0,0,300,-300
J 0
(-8950 3850);
DISPLAY 0.468085 (-8950 3850);
PAINT GREEN (-8950 3850);
DISPLAY INVISIBLE (-8950 3850);
FORCEADD NULL..1
(-5150 3850);
FORCEPROP 1 LAST LOCATION SP62
J 0
(-5150 3900);
DISPLAY 1.212766 (-5150 3900);
PAINT GREEN (-5150 3900);
FORCEPROP 1 LAST CLS_PN G380-10013-01
J 0
(-5150 4000);
DISPLAY 1.212766 (-5150 4000);
PAINT GREEN (-5150 4000);
FORCEPROP 1 LAST PATH I55
J 0
(-5100 3900);
DISPLAY 1.212766 (-5100 3900);
PAINT GREEN (-5100 3900);
DISPLAY INVISIBLE (-5100 3900);
FORCEPROP 1 LAST CDS_LMAN_SYM_OUTLINE 0,0,300,-300
J 0
(-5150 3850);
DISPLAY 0.468085 (-5150 3850);
PAINT GREEN (-5150 3850);
DISPLAY INVISIBLE (-5150 3850);
FORCEPROP 2 LAST CDS_LIB mech
J 0
(-5150 3850);
DISPLAY INVISIBLE (-5150 3850);
FORCEADD NULL..1
(-4200 3850);
FORCEPROP 1 LAST CLS_PN G380-10013-01
J 0
(-4200 4000);
DISPLAY 1.212766 (-4200 4000);
PAINT GREEN (-4200 4000);
FORCEPROP 1 LAST LOCATION SP63
J 0
(-4200 3900);
DISPLAY 1.212766 (-4200 3900);
PAINT GREEN (-4200 3900);
FORCEPROP 1 LAST PATH I56
J 0
(-4150 3900);
DISPLAY 1.212766 (-4150 3900);
PAINT GREEN (-4150 3900);
DISPLAY INVISIBLE (-4150 3900);
FORCEPROP 1 LAST CDS_LMAN_SYM_OUTLINE 0,0,300,-300
J 0
(-4200 3850);
DISPLAY 0.468085 (-4200 3850);
PAINT GREEN (-4200 3850);
DISPLAY INVISIBLE (-4200 3850);
FORCEPROP 2 LAST CDS_LIB mech
J 0
(-4200 3850);
DISPLAY INVISIBLE (-4200 3850);
FORCEADD NULL..1
(-3250 3850);
FORCEPROP 1 LAST LOCATION SP64
J 0
(-3250 3900);
DISPLAY 1.212766 (-3250 3900);
PAINT GREEN (-3250 3900);
FORCEPROP 1 LAST CLS_PN G380-10013-01
J 0
(-3250 4000);
DISPLAY 1.212766 (-3250 4000);
PAINT GREEN (-3250 4000);
FORCEPROP 1 LAST PATH I57
J 0
(-3200 3900);
DISPLAY 1.212766 (-3200 3900);
PAINT GREEN (-3200 3900);
DISPLAY INVISIBLE (-3200 3900);
FORCEPROP 1 LAST CDS_LMAN_SYM_OUTLINE 0,0,300,-300
J 0
(-3250 3850);
DISPLAY 0.468085 (-3250 3850);
PAINT GREEN (-3250 3850);
DISPLAY INVISIBLE (-3250 3850);
FORCEPROP 2 LAST CDS_LIB mech
J 0
(-3250 3850);
DISPLAY INVISIBLE (-3250 3850);
FORCEADD NULL..1
(-2300 3850);
FORCEPROP 1 LAST LOCATION SP65
J 0
(-2300 3900);
DISPLAY 1.212766 (-2300 3900);
PAINT GREEN (-2300 3900);
FORCEPROP 1 LAST CLS_PN G380-10013-01
J 0
(-2300 4000);
DISPLAY 1.212766 (-2300 4000);
PAINT GREEN (-2300 4000);
FORCEPROP 1 LAST PATH I58
J 0
(-2250 3900);
DISPLAY 1.212766 (-2250 3900);
PAINT GREEN (-2250 3900);
DISPLAY INVISIBLE (-2250 3900);
FORCEPROP 1 LAST CDS_LMAN_SYM_OUTLINE 0,0,300,-300
J 0
(-2300 3850);
DISPLAY 0.468085 (-2300 3850);
PAINT GREEN (-2300 3850);
DISPLAY INVISIBLE (-2300 3850);
FORCEPROP 2 LAST CDS_LIB mech
J 0
(-2300 3850);
DISPLAY INVISIBLE (-2300 3850);
FORCEADD NULL..1
(-8000 4400);
FORCEPROP 1 LAST CLS_PN G380-10013-01
J 0
(-8000 4550);
DISPLAY 1.212766 (-8000 4550);
PAINT GREEN (-8000 4550);
FORCEPROP 1 LAST LOCATION SP47
J 0
(-8000 4450);
DISPLAY 1.212766 (-8000 4450);
PAINT GREEN (-8000 4450);
FORCEPROP 1 LAST CDS_LMAN_SYM_OUTLINE 0,0,300,-300
J 0
(-8000 4400);
DISPLAY 0.468085 (-8000 4400);
PAINT GREEN (-8000 4400);
DISPLAY INVISIBLE (-8000 4400);
FORCEPROP 2 LAST CDS_LIB mech
J 0
(-8000 4400);
DISPLAY INVISIBLE (-8000 4400);
FORCEPROP 1 LAST PATH I59
J 0
(-7950 4450);
DISPLAY 1.212766 (-7950 4450);
PAINT GREEN (-7950 4450);
DISPLAY INVISIBLE (-7950 4450);
FORCEADD GND_SG..1
(-5300 5650);
FORCEPROP 3 LASTPIN (-5250 5700) SIG_NAME SG\g
J 0
(-5240 5710);
DISPLAY 0.659574 (-5240 5710);
PAINT MONO (-5240 5710);
DISPLAY INVISIBLE (-5240 5710);
FORCEPROP 1 LAST HDL_POWER SG
J 1
(-5245 5555);
DISPLAY 0.808511 (-5245 5555);
PAINT GREEN (-5245 5555);
FORCEPROP 1 LAST PATH I6
J 0
(-5265 5650);
DISPLAY 0.808511 (-5265 5650);
PAINT GREEN (-5265 5650);
DISPLAY INVISIBLE (-5265 5650);
FORCEPROP 1 LAST CDS_LMAN_SYM_OUTLINE 0,0,100,-50
J 0
(-5300 5650);
DISPLAY 0.468085 (-5300 5650);
PAINT GREEN (-5300 5650);
DISPLAY INVISIBLE (-5300 5650);
FORCEPROP 2 LAST CDS_LIB cls
J 0
(-5300 5650);
DISPLAY INVISIBLE (-5300 5650);
FORCEPROP 1 LAST BODY_TYPE PLUMBING
J 0
(-5285 5635);
DISPLAY 0.808511 (-5285 5635);
PAINT GREEN (-5285 5635);
DISPLAY INVISIBLE (-5285 5635);
FORCEADD NULL..1
(-7050 4400);
FORCEPROP 1 LAST CLS_PN G380-10013-01
J 0
(-7050 4550);
DISPLAY 1.212766 (-7050 4550);
PAINT GREEN (-7050 4550);
FORCEPROP 1 LAST LOCATION SP48
J 0
(-7050 4450);
DISPLAY 1.212766 (-7050 4450);
PAINT GREEN (-7050 4450);
FORCEPROP 1 LAST CDS_LMAN_SYM_OUTLINE 0,0,300,-300
J 0
(-7050 4400);
DISPLAY 0.468085 (-7050 4400);
PAINT GREEN (-7050 4400);
DISPLAY INVISIBLE (-7050 4400);
FORCEPROP 2 LAST CDS_LIB mech
J 0
(-7050 4400);
DISPLAY INVISIBLE (-7050 4400);
FORCEPROP 1 LAST PATH I60
J 0
(-7000 4450);
DISPLAY 1.212766 (-7000 4450);
PAINT GREEN (-7000 4450);
DISPLAY INVISIBLE (-7000 4450);
FORCEADD NULL..1
(-2300 4400);
FORCEPROP 1 LAST CLS_PN G380-10013-01
J 0
(-2300 4550);
DISPLAY 1.212766 (-2300 4550);
PAINT GREEN (-2300 4550);
FORCEPROP 1 LAST LOCATION SP53
J 0
(-2300 4450);
DISPLAY 1.212766 (-2300 4450);
PAINT GREEN (-2300 4450);
FORCEPROP 2 LAST CDS_LIB mech
J 0
(-2300 4400);
DISPLAY INVISIBLE (-2300 4400);
FORCEPROP 1 LAST CDS_LMAN_SYM_OUTLINE 0,0,300,-300
J 0
(-2300 4400);
DISPLAY 0.468085 (-2300 4400);
PAINT GREEN (-2300 4400);
DISPLAY INVISIBLE (-2300 4400);
FORCEPROP 1 LAST PATH I61
J 0
(-2250 4450);
DISPLAY 1.212766 (-2250 4450);
PAINT GREEN (-2250 4450);
DISPLAY INVISIBLE (-2250 4450);
FORCEADD NULL..1
(-3250 4400);
FORCEPROP 1 LAST CLS_PN G380-10013-01
J 0
(-3250 4550);
DISPLAY 1.212766 (-3250 4550);
PAINT GREEN (-3250 4550);
FORCEPROP 1 LAST LOCATION SP52
J 0
(-3250 4450);
DISPLAY 1.212766 (-3250 4450);
PAINT GREEN (-3250 4450);
FORCEPROP 2 LAST CDS_LIB mech
J 0
(-3250 4400);
DISPLAY INVISIBLE (-3250 4400);
FORCEPROP 1 LAST CDS_LMAN_SYM_OUTLINE 0,0,300,-300
J 0
(-3250 4400);
DISPLAY 0.468085 (-3250 4400);
PAINT GREEN (-3250 4400);
DISPLAY INVISIBLE (-3250 4400);
FORCEPROP 1 LAST PATH I62
J 0
(-3200 4450);
DISPLAY 1.212766 (-3200 4450);
PAINT GREEN (-3200 4450);
DISPLAY INVISIBLE (-3200 4450);
FORCEADD NULL..1
(-4200 4400);
FORCEPROP 1 LAST CLS_PN G380-10013-01
J 0
(-4200 4550);
DISPLAY 1.212766 (-4200 4550);
PAINT GREEN (-4200 4550);
FORCEPROP 1 LAST LOCATION SP51
J 0
(-4200 4450);
DISPLAY 1.212766 (-4200 4450);
PAINT GREEN (-4200 4450);
FORCEPROP 2 LAST CDS_LIB mech
J 0
(-4200 4400);
DISPLAY INVISIBLE (-4200 4400);
FORCEPROP 1 LAST CDS_LMAN_SYM_OUTLINE 0,0,300,-300
J 0
(-4200 4400);
DISPLAY 0.468085 (-4200 4400);
PAINT GREEN (-4200 4400);
DISPLAY INVISIBLE (-4200 4400);
FORCEPROP 1 LAST PATH I63
J 0
(-4150 4450);
DISPLAY 1.212766 (-4150 4450);
PAINT GREEN (-4150 4450);
DISPLAY INVISIBLE (-4150 4450);
FORCEADD NULL..1
(-5150 4400);
FORCEPROP 1 LAST LOCATION SP50
J 0
(-5150 4450);
DISPLAY 1.212766 (-5150 4450);
PAINT GREEN (-5150 4450);
FORCEPROP 1 LAST CLS_PN G380-10013-01
J 0
(-5150 4550);
DISPLAY 1.212766 (-5150 4550);
PAINT GREEN (-5150 4550);
FORCEPROP 2 LAST CDS_LIB mech
J 0
(-5150 4400);
DISPLAY INVISIBLE (-5150 4400);
FORCEPROP 1 LAST CDS_LMAN_SYM_OUTLINE 0,0,300,-300
J 0
(-5150 4400);
DISPLAY 0.468085 (-5150 4400);
PAINT GREEN (-5150 4400);
DISPLAY INVISIBLE (-5150 4400);
FORCEPROP 1 LAST PATH I64
J 0
(-5100 4450);
DISPLAY 1.212766 (-5100 4450);
PAINT GREEN (-5100 4450);
DISPLAY INVISIBLE (-5100 4450);
FORCEADD NULL..1
(-6100 4400);
FORCEPROP 1 LAST CLS_PN G380-10013-01
J 0
(-6100 4550);
DISPLAY 1.212766 (-6100 4550);
PAINT GREEN (-6100 4550);
FORCEPROP 1 LAST LOCATION SP49
J 0
(-6100 4450);
DISPLAY 1.212766 (-6100 4450);
PAINT GREEN (-6100 4450);
FORCEPROP 1 LAST CDS_LMAN_SYM_OUTLINE 0,0,300,-300
J 0
(-6100 4400);
DISPLAY 0.468085 (-6100 4400);
PAINT GREEN (-6100 4400);
DISPLAY INVISIBLE (-6100 4400);
FORCEPROP 2 LAST CDS_LIB mech
J 0
(-6100 4400);
DISPLAY INVISIBLE (-6100 4400);
FORCEPROP 1 LAST PATH I65
J 0
(-6050 4450);
DISPLAY 1.212766 (-6050 4450);
PAINT GREEN (-6050 4450);
DISPLAY INVISIBLE (-6050 4450);
FORCEADD NULL..1
(-8950 4400);
FORCEPROP 1 LAST CLS_PN G380-10013-01
J 0
(-8950 4550);
DISPLAY 1.212766 (-8950 4550);
PAINT GREEN (-8950 4550);
FORCEPROP 1 LAST LOCATION SP46
J 0
(-8950 4450);
DISPLAY 1.212766 (-8950 4450);
PAINT GREEN (-8950 4450);
FORCEPROP 1 LAST CDS_LMAN_SYM_OUTLINE 0,0,300,-300
J 0
(-8950 4400);
DISPLAY 0.468085 (-8950 4400);
PAINT GREEN (-8950 4400);
DISPLAY INVISIBLE (-8950 4400);
FORCEPROP 2 LAST CDS_LIB mech
J 0
(-8950 4400);
DISPLAY INVISIBLE (-8950 4400);
FORCEPROP 1 LAST PATH I66
J 0
(-8900 4450);
DISPLAY 1.212766 (-8900 4450);
PAINT GREEN (-8900 4450);
DISPLAY INVISIBLE (-8900 4450);
FORCEADD NULL..1
(-9900 4400);
FORCEPROP 1 LAST CLS_PN G380-10013-01
J 0
(-9900 4550);
DISPLAY 1.212766 (-9900 4550);
PAINT GREEN (-9900 4550);
FORCEPROP 1 LAST LOCATION SP45
J 0
(-9900 4450);
DISPLAY 1.212766 (-9900 4450);
PAINT GREEN (-9900 4450);
FORCEPROP 1 LAST CDS_LMAN_SYM_OUTLINE 0,0,300,-300
J 0
(-9900 4400);
DISPLAY 0.468085 (-9900 4400);
PAINT GREEN (-9900 4400);
DISPLAY INVISIBLE (-9900 4400);
FORCEPROP 2 LAST CDS_LIB mech
J 0
(-9900 4400);
DISPLAY INVISIBLE (-9900 4400);
FORCEPROP 1 LAST PATH I67
J 0
(-9850 4450);
DISPLAY 1.212766 (-9850 4450);
PAINT GREEN (-9850 4450);
DISPLAY INVISIBLE (-9850 4450);
FORCEADD NULL..1
(-10850 4400);
FORCEPROP 1 LAST CLS_PN G380-10013-01
J 0
(-10850 4550);
DISPLAY 1.212766 (-10850 4550);
PAINT GREEN (-10850 4550);
FORCEPROP 1 LAST LOCATION SP44
J 0
(-10850 4450);
DISPLAY 1.212766 (-10850 4450);
PAINT GREEN (-10850 4450);
FORCEPROP 1 LAST CDS_LMAN_SYM_OUTLINE 0,0,300,-300
J 0
(-10850 4400);
DISPLAY 0.468085 (-10850 4400);
PAINT GREEN (-10850 4400);
DISPLAY INVISIBLE (-10850 4400);
FORCEPROP 2 LAST CDS_LIB mech
J 0
(-10850 4400);
DISPLAY INVISIBLE (-10850 4400);
FORCEPROP 1 LAST PATH I68
J 0
(-10800 4450);
DISPLAY 1.212766 (-10800 4450);
PAINT GREEN (-10800 4450);
DISPLAY INVISIBLE (-10800 4450);
FORCEADD NULL..1
(-11800 4400);
FORCEPROP 1 LAST CLS_PN G380-10013-01
J 0
(-11800 4550);
DISPLAY 1.212766 (-11800 4550);
PAINT GREEN (-11800 4550);
FORCEPROP 1 LAST LOCATION SP43
J 0
(-11800 4450);
DISPLAY 1.212766 (-11800 4450);
PAINT GREEN (-11800 4450);
FORCEPROP 1 LAST CDS_LMAN_SYM_OUTLINE 0,0,300,-300
J 0
(-11800 4400);
DISPLAY 0.468085 (-11800 4400);
PAINT GREEN (-11800 4400);
DISPLAY INVISIBLE (-11800 4400);
FORCEPROP 2 LAST CDS_LIB mech
J 0
(-11800 4400);
DISPLAY INVISIBLE (-11800 4400);
FORCEPROP 1 LAST PATH I69
J 0
(-11750 4450);
DISPLAY 1.212766 (-11750 4450);
PAINT GREEN (-11750 4450);
DISPLAY INVISIBLE (-11750 4450);
FORCEADD MEC_MTH8..1
(-6500 6550);
FORCEPROP 0 LASTPIN (-6600 5800) $PN 8
J 2
(-6610 5810);
DISPLAY 0.680851 (-6610 5810);
PAINT MONO (-6610 5810);
FORCEPROP 0 LASTPIN (-6600 5900) $PN 7
J 2
(-6610 5910);
DISPLAY 0.680851 (-6610 5910);
PAINT MONO (-6610 5910);
FORCEPROP 0 LASTPIN (-6600 6000) $PN 6
J 2
(-6610 6010);
DISPLAY 0.680851 (-6610 6010);
PAINT MONO (-6610 6010);
FORCEPROP 0 LASTPIN (-6600 6100) $PN 5
J 2
(-6610 6110);
DISPLAY 0.680851 (-6610 6110);
PAINT MONO (-6610 6110);
FORCEPROP 0 LASTPIN (-6600 6200) $PN 4
J 2
(-6610 6210);
DISPLAY 0.680851 (-6610 6210);
PAINT MONO (-6610 6210);
FORCEPROP 0 LASTPIN (-6600 6300) $PN 3
J 2
(-6610 6310);
DISPLAY 0.680851 (-6610 6310);
PAINT MONO (-6610 6310);
FORCEPROP 0 LASTPIN (-6600 6500) $PN 1
J 2
(-6610 6510);
DISPLAY 0.680851 (-6610 6510);
PAINT MONO (-6610 6510);
FORCEPROP 0 LASTPIN (-6600 6400) $PN 2
J 2
(-6610 6410);
DISPLAY 0.680851 (-6610 6410);
PAINT MONO (-6610 6410);
FORCEPROP 1 LAST $LOCATION ME9
J 0
(-6500 6600);
DISPLAY 0.808511 (-6500 6600);
PAINT GREEN (-6500 6600);
FORCEPROP 0 LAST CDS_SEC 1
J 0
(-6500 6650);
DISPLAY 1.021277 (-6500 6650);
DISPLAY INVISIBLE (-6500 6650);
FORCEPROP 0 LAST $SEC 1
J 0
(-6500 6650);
DISPLAY 0.680851 (-6500 6650);
PAINT MONO (-6500 6650);
DISPLAY INVISIBLE (-6500 6650);
FORCEPROP 0 LAST CDS_LOCATION ME9
J 0
(-6500 6650);
DISPLAY 1.021277 (-6500 6650);
DISPLAY INVISIBLE (-6500 6650);
FORCEPROP 1 LAST BOM_IGNORE TRUE
J 0
(-6574 6600);
DISPLAY 0.000000 (-6574 6600);
PAINT GREEN (-6574 6600);
DISPLAY INVISIBLE (-6574 6600);
FORCEPROP 1 LAST JEDEC_TYPE MTH125C236N_V8
J 0
(-6574 6600);
DISPLAY 0.000000 (-6574 6600);
PAINT GREEN (-6574 6600);
DISPLAY INVISIBLE (-6574 6600);
FORCEPROP 1 LAST CDS_LMAN_SYM_OUTLINE 0,0,100,-800
J 0
(-6500 6550);
DISPLAY 0.468085 (-6500 6550);
PAINT GREEN (-6500 6550);
DISPLAY INVISIBLE (-6500 6550);
FORCEPROP 2 LAST CDS_LIB mech
J 0
(-6500 6550);
DISPLAY INVISIBLE (-6500 6550);
FORCEPROP 1 LAST PATH I7
J 0
(-6370 6613);
DISPLAY 0.808511 (-6370 6613);
PAINT GREEN (-6370 6613);
DISPLAY INVISIBLE (-6370 6613);
FORCEADD NULL..1
(-12750 4400);
FORCEPROP 1 LAST CLS_PN G380-10013-01
J 0
(-12750 4550);
DISPLAY 1.212766 (-12750 4550);
PAINT GREEN (-12750 4550);
FORCEPROP 1 LAST LOCATION SP42
J 0
(-12750 4450);
DISPLAY 1.212766 (-12750 4450);
PAINT GREEN (-12750 4450);
FORCEPROP 1 LAST CDS_LMAN_SYM_OUTLINE 0,0,300,-300
J 0
(-12750 4400);
DISPLAY 0.468085 (-12750 4400);
PAINT GREEN (-12750 4400);
DISPLAY INVISIBLE (-12750 4400);
FORCEPROP 2 LAST CDS_LIB mech
J 0
(-12750 4400);
DISPLAY INVISIBLE (-12750 4400);
FORCEPROP 1 LAST PATH I70
J 0
(-12700 4450);
DISPLAY 1.212766 (-12700 4450);
PAINT GREEN (-12700 4450);
DISPLAY INVISIBLE (-12700 4450);
FORCEADD GND_SG..1
(-6850 5650);
FORCEPROP 3 LASTPIN (-6800 5700) SIG_NAME SG\g
J 0
(-6790 5710);
DISPLAY 0.659574 (-6790 5710);
PAINT MONO (-6790 5710);
DISPLAY INVISIBLE (-6790 5710);
FORCEPROP 1 LAST HDL_POWER SG
J 1
(-6795 5555);
DISPLAY 0.808511 (-6795 5555);
PAINT GREEN (-6795 5555);
FORCEPROP 1 LAST PATH I8
J 0
(-6815 5650);
DISPLAY 0.808511 (-6815 5650);
PAINT GREEN (-6815 5650);
DISPLAY INVISIBLE (-6815 5650);
FORCEPROP 1 LAST BODY_TYPE PLUMBING
J 0
(-6835 5635);
DISPLAY 0.808511 (-6835 5635);
PAINT GREEN (-6835 5635);
DISPLAY INVISIBLE (-6835 5635);
FORCEPROP 1 LAST CDS_LMAN_SYM_OUTLINE 0,0,100,-50
J 0
(-6850 5650);
DISPLAY 0.468085 (-6850 5650);
PAINT GREEN (-6850 5650);
DISPLAY INVISIBLE (-6850 5650);
FORCEPROP 2 LAST CDS_LIB cls
J 0
(-6850 5650);
DISPLAY INVISIBLE (-6850 5650);
FORCEADD NULL..1
(-8000 3300);
FORCEPROP 1 LAST LOCATION SP71
J 0
(-8000 3350);
DISPLAY 1.212766 (-8000 3350);
PAINT GREEN (-8000 3350);
FORCEPROP 1 LAST CLS_PN G380-10013-01
J 0
(-8000 3450);
DISPLAY 1.212766 (-8000 3450);
PAINT GREEN (-8000 3450);
FORCEPROP 1 LAST CDS_LMAN_SYM_OUTLINE 0,0,300,-300
J 0
(-8000 3300);
DISPLAY 0.468085 (-8000 3300);
PAINT GREEN (-8000 3300);
DISPLAY INVISIBLE (-8000 3300);
FORCEPROP 2 LAST CDS_LIB mech
J 0
(-8000 3300);
DISPLAY INVISIBLE (-8000 3300);
FORCEPROP 1 LAST PATH I83
J 0
(-7950 3350);
DISPLAY 1.212766 (-7950 3350);
PAINT GREEN (-7950 3350);
DISPLAY INVISIBLE (-7950 3350);
FORCEADD NULL..1
(-8950 3300);
FORCEPROP 1 LAST LOCATION SP70
J 0
(-8950 3350);
DISPLAY 1.212766 (-8950 3350);
PAINT GREEN (-8950 3350);
FORCEPROP 1 LAST CLS_PN G380-10013-01
J 0
(-8950 3450);
DISPLAY 1.212766 (-8950 3450);
PAINT GREEN (-8950 3450);
FORCEPROP 1 LAST CDS_LMAN_SYM_OUTLINE 0,0,300,-300
J 0
(-8950 3300);
DISPLAY 0.468085 (-8950 3300);
PAINT GREEN (-8950 3300);
DISPLAY INVISIBLE (-8950 3300);
FORCEPROP 2 LAST CDS_LIB mech
J 0
(-8950 3300);
DISPLAY INVISIBLE (-8950 3300);
FORCEPROP 1 LAST PATH I84
J 0
(-8900 3350);
DISPLAY 1.212766 (-8900 3350);
PAINT GREEN (-8900 3350);
DISPLAY INVISIBLE (-8900 3350);
FORCEADD NULL..1
(-9900 3300);
FORCEPROP 1 LAST CLS_PN G380-10013-01
J 0
(-9900 3450);
DISPLAY 1.212766 (-9900 3450);
PAINT GREEN (-9900 3450);
FORCEPROP 1 LAST LOCATION SP69
J 0
(-9900 3350);
DISPLAY 1.212766 (-9900 3350);
PAINT GREEN (-9900 3350);
FORCEPROP 1 LAST CDS_LMAN_SYM_OUTLINE 0,0,300,-300
J 0
(-9900 3300);
DISPLAY 0.468085 (-9900 3300);
PAINT GREEN (-9900 3300);
DISPLAY INVISIBLE (-9900 3300);
FORCEPROP 2 LAST CDS_LIB mech
J 0
(-9900 3300);
DISPLAY INVISIBLE (-9900 3300);
FORCEPROP 1 LAST PATH I85
J 0
(-9850 3350);
DISPLAY 1.212766 (-9850 3350);
PAINT GREEN (-9850 3350);
DISPLAY INVISIBLE (-9850 3350);
FORCEADD NULL..1
(-10850 3300);
FORCEPROP 1 LAST LOCATION SP68
J 0
(-10850 3350);
DISPLAY 1.212766 (-10850 3350);
PAINT GREEN (-10850 3350);
FORCEPROP 1 LAST CLS_PN G380-10013-01
J 0
(-10850 3450);
DISPLAY 1.212766 (-10850 3450);
PAINT GREEN (-10850 3450);
FORCEPROP 1 LAST CDS_LMAN_SYM_OUTLINE 0,0,300,-300
J 0
(-10850 3300);
DISPLAY 0.468085 (-10850 3300);
PAINT GREEN (-10850 3300);
DISPLAY INVISIBLE (-10850 3300);
FORCEPROP 2 LAST CDS_LIB mech
J 0
(-10850 3300);
DISPLAY INVISIBLE (-10850 3300);
FORCEPROP 1 LAST PATH I89
J 0
(-10800 3350);
DISPLAY 1.212766 (-10800 3350);
PAINT GREEN (-10800 3350);
DISPLAY INVISIBLE (-10800 3350);
FORCEADD NULL..1
(-11800 3300);
FORCEPROP 1 LAST CLS_PN G380-10013-01
J 0
(-11800 3450);
DISPLAY 1.212766 (-11800 3450);
PAINT GREEN (-11800 3450);
FORCEPROP 1 LAST LOCATION SP67
J 0
(-11800 3350);
DISPLAY 1.212766 (-11800 3350);
PAINT GREEN (-11800 3350);
FORCEPROP 1 LAST CDS_LMAN_SYM_OUTLINE 0,0,300,-300
J 0
(-11800 3300);
DISPLAY 0.468085 (-11800 3300);
PAINT GREEN (-11800 3300);
DISPLAY INVISIBLE (-11800 3300);
FORCEPROP 2 LAST CDS_LIB mech
J 0
(-11800 3300);
DISPLAY INVISIBLE (-11800 3300);
FORCEPROP 1 LAST PATH I90
J 0
(-11750 3350);
DISPLAY 1.212766 (-11750 3350);
PAINT GREEN (-11750 3350);
DISPLAY INVISIBLE (-11750 3350);
FORCEADD NULL..1
(-12750 3300);
FORCEPROP 1 LAST LOCATION SP66
J 0
(-12750 3350);
DISPLAY 1.212766 (-12750 3350);
PAINT GREEN (-12750 3350);
FORCEPROP 1 LAST CLS_PN G380-10013-01
J 0
(-12750 3450);
DISPLAY 1.212766 (-12750 3450);
PAINT GREEN (-12750 3450);
FORCEPROP 1 LAST CDS_LMAN_SYM_OUTLINE 0,0,300,-300
J 0
(-12750 3300);
DISPLAY 0.468085 (-12750 3300);
PAINT GREEN (-12750 3300);
DISPLAY INVISIBLE (-12750 3300);
FORCEPROP 2 LAST CDS_LIB mech
J 0
(-12750 3300);
DISPLAY INVISIBLE (-12750 3300);
FORCEPROP 1 LAST PATH I93
J 0
(-12700 3350);
DISPLAY 1.212766 (-12700 3350);
PAINT GREEN (-12700 3350);
DISPLAY INVISIBLE (-12700 3350);
FORCEADD SHEET_A1..1
(850 -1900);
FORCEPROP 2 LAST CUSTOM_TXT_CDS <XR_PAGE_TITLE>
J 0
(-14720 9450);
DISPLAY 0.638298 (-14720 9450);
PAINT PINK (-14720 9450);
FORCEPROP 1 LAST CUSTOM_TXT_CDS <DOCNO>
J 0
(-1200 -1515);
DISPLAY 0.978723 (-1200 -1515);
FORCEPROP 1 LAST CUSTOM_TXT_CDS <CON_PAGE_NUM>
J 0
(-1305 -1850);
DISPLAY 0.978723 (-1305 -1850);
FORCEPROP 1 LAST CUSTOM_TXT_CDS <DATE>
J 0
(150 -1725);
DISPLAY 0.978723 (150 -1725);
FORCEPROP 1 LAST CUSTOM_TXT_CDS <TITLE>
J 1
(-935 -1270);
DISPLAY 0.978723 (-935 -1270);
FORCEPROP 1 LAST CUSTOM_TXT_CDS <DESIGNER>
J 0
(150 -1300);
DISPLAY 0.978723 (150 -1300);
FORCEPROP 1 LAST CUSTOM_TXT_CDS <CON_TOTAL_PAGES>
J 0
(-995 -1850);
DISPLAY 0.808511 (-995 -1850);
FORCEPROP 1 LAST CUSTOM_TXT_CDS <ASSY_PN>
J 0
(-1200 -1725);
DISPLAY 0.978723 (-1200 -1725);
FORCEPROP 1 LAST CUSTOM_TXT_CDS <DOCREV>
J 0
(150 -1525);
DISPLAY 0.978723 (150 -1525);
FORCEPROP 1 LAST TITLE MECH_PART
J 0
(-1650 -1050);
DISPLAY 3.042553 (-1650 -1050);
PAINT GREEN (-1650 -1050);
FORCEPROP 2 LAST CDS_LIB cls
J 0
(850 -1900);
DISPLAY INVISIBLE (850 -1900);
FORCEPROP 1 LAST CDS_LMAN_SYM_OUTLINE -15850,11500,200,-200
J 0
(850 -1900);
DISPLAY 0.468085 (850 -1900);
PAINT GREEN (850 -1900);
DISPLAY INVISIBLE (850 -1900);
FORCEPROP 2 LAST PAGE_BORDER TRUE
J 0
(-14720 9450);
DISPLAY 0.638298 (-14720 9450);
PAINT PINK (-14720 9450);
DISPLAY INVISIBLE (-14720 9450);
FORCEPROP 1 LAST COMMENT_BODY TRUE
J 0
(860 -1845);
DISPLAY 0.808511 (860 -1845);
PAINT GREEN (860 -1845);
DISPLAY INVISIBLE (860 -1845);
FORCEPROP 2 LAST CDS_XR_PAGE_TITLE CR-34 : @TIMECARD_LIB.TIMECARD(SCH_1):PAGE34
J 0
(-14720 9450);
DISPLAY 0.638298 (-14720 9450);
PAINT PINK (-14720 9450);
DISPLAY INVISIBLE (-14720 9450);
WIRE 16 -1 (-6800 5700)(-6800 5800);
WIRE 16 -1 (-5250 5700)(-5250 5800);
WIRE 16 -1 (-3700 5700)(-3700 5800);
WIRE 16 -1 (-2150 5700)(-2150 5800);
WIRE 16 -1 (-10950 6000)(-10950 6150);
WIRE 16 -1 (-8900 6000)(-8900 6150);
WIRE 16 -1 (-6600 6500)(-6800 6500);
WIRE 16 -1 (-6800 6400)(-6800 6500);
WIRE 16 -1 (-6600 6400)(-6800 6400);
WIRE 16 -1 (-6800 6300)(-6800 6400);
WIRE 16 -1 (-6600 6300)(-6800 6300);
WIRE 16 -1 (-6800 6200)(-6800 6300);
WIRE 16 -1 (-6600 6200)(-6800 6200);
WIRE 16 -1 (-6800 6100)(-6600 6100);
WIRE 16 -1 (-6800 6100)(-6800 6200);
WIRE 16 -1 (-6800 6000)(-6800 6100);
WIRE 16 -1 (-6600 6000)(-6800 6000);
WIRE 16 -1 (-6800 5900)(-6800 6000);
WIRE 16 -1 (-6600 5900)(-6800 5900);
WIRE 16 -1 (-6800 5800)(-6800 5900);
WIRE 16 -1 (-6600 5800)(-6800 5800);
WIRE 16 -1 (-5050 6500)(-5250 6500);
WIRE 16 -1 (-5250 6400)(-5250 6500);
WIRE 16 -1 (-5050 6400)(-5250 6400);
WIRE 16 -1 (-5250 6300)(-5250 6400);
WIRE 16 -1 (-5050 6300)(-5250 6300);
WIRE 16 -1 (-5250 6200)(-5250 6300);
WIRE 16 -1 (-5050 6200)(-5250 6200);
WIRE 16 -1 (-5050 6100)(-5250 6100);
WIRE 16 -1 (-5250 6100)(-5250 6200);
WIRE 16 -1 (-5250 6000)(-5250 6100);
WIRE 16 -1 (-5050 6000)(-5250 6000);
WIRE 16 -1 (-5250 5900)(-5250 6000);
WIRE 16 -1 (-5050 5900)(-5250 5900);
WIRE 16 -1 (-5250 5800)(-5250 5900);
WIRE 16 -1 (-5050 5800)(-5250 5800);
WIRE 16 -1 (-3500 6500)(-3700 6500);
WIRE 16 -1 (-3700 6400)(-3700 6500);
WIRE 16 -1 (-3500 6400)(-3700 6400);
WIRE 16 -1 (-3700 6300)(-3700 6400);
WIRE 16 -1 (-3500 6300)(-3700 6300);
WIRE 16 -1 (-3700 6200)(-3700 6300);
WIRE 16 -1 (-3500 6200)(-3700 6200);
WIRE 16 -1 (-3500 6100)(-3700 6100);
WIRE 16 -1 (-3700 6100)(-3700 6200);
WIRE 16 -1 (-3700 6000)(-3700 6100);
WIRE 16 -1 (-3500 6000)(-3700 6000);
WIRE 16 -1 (-3700 5900)(-3700 6000);
WIRE 16 -1 (-3500 5900)(-3700 5900);
WIRE 16 -1 (-3700 5800)(-3700 5900);
WIRE 16 -1 (-3500 5800)(-3700 5800);
WIRE 16 -1 (-1950 6500)(-2150 6500);
WIRE 16 -1 (-2150 6400)(-2150 6500);
WIRE 16 -1 (-1950 6400)(-2150 6400);
WIRE 16 -1 (-2150 6300)(-2150 6400);
WIRE 16 -1 (-1950 6300)(-2150 6300);
WIRE 16 -1 (-2150 6200)(-2150 6300);
WIRE 16 -1 (-1950 6200)(-2150 6200);
WIRE 16 -1 (-2150 6100)(-2150 6200);
WIRE 16 -1 (-1950 6100)(-2150 6100);
WIRE 16 -1 (-2150 6000)(-2150 6100);
WIRE 16 -1 (-1950 6000)(-2150 6000);
WIRE 16 -1 (-2150 5900)(-2150 6000);
WIRE 16 -1 (-1950 5900)(-2150 5900);
WIRE 16 -1 (-2150 5800)(-2150 5900);
WIRE 16 -1 (-1950 5800)(-2150 5800);
WIRE 16 -1 (-11250 6850)(-10950 6850);
WIRE 16 -1 (-10950 6150)(-11250 6150);
WIRE 16 -1 (-10950 6850)(-10950 6150);
WIRE 16 -1 (-9200 6850)(-8900 6850);
WIRE 16 -1 (-8900 6150)(-9200 6150);
WIRE 16 -1 (-8900 6850)(-8900 6150);
WIRE 16 273 (-1150 8350)(-1150 7150);
WIRE 16 273 (-1150 8350)(-7950 8350);
WIRE 16 273 (-12800 8350)(-7950 8350);
WIRE 16 273 (-1150 5400)(-1150 7150);
WIRE 16 273 (-7950 7150)(-1150 7150);
WIRE 16 273 (-7950 7150)(-7950 8350);
WIRE 16 273 (-7950 5400)(-7950 7150);
WIRE 16 273 (-1150 5400)(-7950 5400);
WIRE 16 273 (-12800 8350)(-12800 5400);
WIRE 16 273 (-12800 5400)(-7950 5400);
DOT 1 (-7950 8350);
DOT 1 (-1150 7150);
DOT 1 (-2150 6300);
DOT 1 (-2150 6200);
DOT 1 (-2150 6400);
DOT 1 (-3700 6300);
DOT 1 (-3700 6200);
DOT 1 (-3700 6400);
DOT 1 (-2150 6100);
DOT 1 (-2150 6000);
DOT 1 (-2150 5900);
DOT 1 (-2150 5800);
DOT 1 (-3700 6100);
DOT 1 (-3700 6000);
DOT 1 (-3700 5900);
DOT 1 (-3700 5800);
DOT 1 (-5250 6200);
DOT 1 (-5250 6400);
DOT 1 (-5250 6300);
DOT 1 (-5250 6000);
DOT 1 (-5250 6100);
DOT 1 (-5250 5900);
DOT 1 (-5250 5800);
DOT 1 (-6800 6300);
DOT 1 (-6800 6200);
DOT 1 (-6800 6400);
DOT 1 (-7950 7150);
DOT 1 (-6800 6100);
DOT 1 (-6800 6000);
DOT 1 (-6800 5900);
DOT 1 (-6800 5800);
DOT 1 (-7950 5400);
DOT 1 (-8900 6150);
DOT 1 (-10950 6150);
FORCENOTE
SOLDER PREFORM,ALLOY SAC305,0603H
(-12750 4800) 0;
DISPLAY LEFT (-12750 4800);
DISPLAY 3.148936 (-12750 4800);
FORCENOTE
SOLDER PREFORM,ALLOY SAC305,0201
(-12750 2350) 0;
DISPLAY LEFT (-12750 2350);
DISPLAY 3.148936 (-12750 2350);
FORCENOTE
MOUNTING HOLES FOR THE PCIE CARD
(-6800 6900) 0;
DISPLAY LEFT (-6800 6900);
DISPLAY 2.510638 (-6800 6900);
FORCENOTE
MOUNTING HOLES FOR MAC MODULE.
(-6800 8000) 0;
DISPLAY LEFT (-6800 8000);
DISPLAY 2.510638 (-6800 8000);
FORCENOTE
STANDOFFS FOR GPS MODULE.
(-11800 7700) 0;
DISPLAY LEFT (-11800 7700);
DISPLAY 2.510638 (-11800 7700);
QUIT
